G04 ================== begin FILE IDENTIFICATION RECORD ==================*
G04 Layout Name:  13130-1b.brd*
G04 Film Name:    DRILL*
G04 File Format:  Gerber RS274X*
G04 File Origin:  Cadence Allegro 16.5-S037*
G04 Origin Date:  Thu Nov 13 17:26:21 2014*
G04 *
G04 Layer:  MANUFACTURING/NCLEGEND-1-12*
G04 Layer:  MANUFACTURING/DRILL SIZE*
G04 Layer:  DRAWING FORMAT/LAYER_PCB_STORY*
G04 Layer:  DRAWING FORMAT/LAYER_DRILL*
G04 Layer:  BOARD GEOMETRY/PANEL_OUTLINE*
G04 *
G04 Offset:    (0.00 0.00)*
G04 Mirror:    No*
G04 Mode:      Positive*
G04 Rotation:  0*
G04 FullContactRelief:  No*
G04 UndefLineWidth:     6.00*
G04 ================== end FILE IDENTIFICATION RECORD ====================*
%FSLAX35Y35*MOIN*%
%IR0*IPPOS*OFA0.00000B0.00000*MIA0B0*SFA1.00000B1.00000*%
%AMMACRO15*
1,1,.006,.0325,.024375*
20,1,.006,.0325,.024375,.0325,-.024375,0.0*
1,1,.006,.0325,-.024375*
20,1,.006,.0325,-.024375,-.0325,-.024375,0.0*
1,1,.006,-.0325,-.024375*
20,1,.006,-.0325,-.024375,-.0325,.024375,0.0*
1,1,.006,-.0325,.024375*
20,1,.006,-.0325,.024375,.0325,.024375,0.0*
1,1,.006,.0325,.024375*
1,1,.006,-.01219,-.01218*
20,1,.006,-.01219,-.01218,-.01219,.01219,0.0*
1,1,.006,-.01219,.01219*
20,1,.006,-.01219,.01219,-.01706,.00732,0.0*
1,1,.006,-.01706,.00732*
1,1,.006,-.01706,-.01218*
20,1,.006,-.01706,-.01218,-.00731,-.01218,0.0*
1,1,.006,-.00731,-.01218*
1,1,.006,.01219,.01219*
20,1,.006,.01219,.01219,.00895,.01138,0.0*
1,1,.006,.00895,.01138*
20,1,.006,.00895,.01138,.00651,.00935,0.0*
1,1,.006,.00651,.00935*
20,1,.006,.00651,.00935,.00488,.00691,0.0*
1,1,.006,.00488,.00691*
20,1,.006,.00488,.00691,.00367,.00366,0.0*
1,1,.006,.00367,.00366*
20,1,.006,.00367,.00366,.00326,0.0,0.0*
1,1,.006,.00326,0.0*
20,1,.006,.00326,0.0,.00367,-.00365,0.0*
1,1,.006,.00367,-.00365*
20,1,.006,.00367,-.00365,.00488,-.0069,0.0*
1,1,.006,.00488,-.0069*
20,1,.006,.00488,-.0069,.00651,-.00934,0.0*
1,1,.006,.00651,-.00934*
20,1,.006,.00651,-.00934,.00895,-.01137,0.0*
1,1,.006,.00895,-.01137*
20,1,.006,.00895,-.01137,.01219,-.01218,0.0*
1,1,.006,.01219,-.01218*
20,1,.006,.01219,-.01218,.01544,-.01137,0.0*
1,1,.006,.01544,-.01137*
20,1,.006,.01544,-.01137,.01788,-.00934,0.0*
1,1,.006,.01788,-.00934*
20,1,.006,.01788,-.00934,.01951,-.0069,0.0*
1,1,.006,.01951,-.0069*
20,1,.006,.01951,-.0069,.02072,-.00365,0.0*
1,1,.006,.02072,-.00365*
20,1,.006,.02072,-.00365,.02113,0.0,0.0*
1,1,.006,.02113,0.0*
20,1,.006,.02113,0.0,.02072,.00366,0.0*
1,1,.006,.02072,.00366*
20,1,.006,.02072,.00366,.01951,.00691,0.0*
1,1,.006,.01951,.00691*
20,1,.006,.01951,.00691,.01788,.00935,0.0*
1,1,.006,.01788,.00935*
20,1,.006,.01788,.00935,.01544,.01138,0.0*
1,1,.006,.01544,.01138*
20,1,.006,.01544,.01138,.01219,.01219,0.0*
1,1,.006,.01219,.01219*
%
%ADD15MACRO15*%
%AMMACRO13*
1,1,.006,.005,.005*
20,1,.006,.005,.005,.005,-.005,0.0*
1,1,.006,.005,-.005*
20,1,.006,.005,-.005,-.005,-.005,0.0*
1,1,.006,-.005,-.005*
20,1,.006,-.005,-.005,-.005,.005,0.0*
1,1,.006,-.005,.005*
20,1,.006,-.005,.005,.005,.005,0.0*
1,1,.006,.005,.005*
1,1,.006,-.00158,.00167*
20,1,.006,-.00158,.00167,-.00108,.00217,0.0*
1,1,.006,-.00108,.00217*
20,1,.006,-.00108,.00217,-.0005,.00242,0.0*
1,1,.006,-.0005,.00242*
20,1,.006,-.0005,.00242,.00017,.0025,0.0*
1,1,.006,.00017,.0025*
20,1,.006,.00017,.0025,.001,.00233,0.0*
1,1,.006,.001,.00233*
20,1,.006,.001,.00233,.00158,.00192,0.0*
1,1,.006,.00158,.00192*
20,1,.006,.00158,.00192,.00175,.00142,0.0*
1,1,.006,.00175,.00142*
20,1,.006,.00175,.00142,.00167,.00092,0.0*
1,1,.006,.00167,.00092*
20,1,.006,.00167,.00092,.00133,.0005,0.0*
1,1,.006,.00133,.0005*
20,1,.006,.00133,.0005,-.00033,-.00033,0.0*
1,1,.006,-.00033,-.00033*
20,1,.006,-.00033,-.00033,-.00108,-.00092,0.0*
1,1,.006,-.00108,-.00092*
20,1,.006,-.00108,-.00092,-.00158,-.00175,0.0*
1,1,.006,-.00158,-.00175*
20,1,.006,-.00158,-.00175,-.00175,-.0025,0.0*
1,1,.006,-.00175,-.0025*
20,1,.006,-.00175,-.0025,.00175,-.0025,0.0*
1,1,.006,.00175,-.0025*
%
%ADD13MACRO13*%
%AMMACRO21*
1,1,.006,.008284,-.02*
20,1,.006,.008284,-.02,-.008284,-.02,0.0*
1,1,.006,-.008284,-.02*
20,1,.006,-.008284,-.02,-.02,-.008284,0.0*
1,1,.006,-.02,-.008284*
20,1,.006,-.02,-.008284,-.02,.008284,0.0*
1,1,.006,-.02,.008284*
20,1,.006,-.02,.008284,-.008284,.02,0.0*
1,1,.006,-.008284,.02*
20,1,.006,-.008284,.02,.008284,.02,0.0*
1,1,.006,.008284,.02*
20,1,.006,.008284,.02,.02,.008284,0.0*
1,1,.006,.02,.008284*
20,1,.006,.02,.008284,.02,-.008284,0.0*
1,1,.006,.02,-.008284*
20,1,.006,.02,-.008284,.008284,-.02,0.0*
1,1,.006,.008284,-.02*
1,1,.006,-.00733,-.007*
20,1,.006,-.00733,-.007,-.00533,-.00867,0.0*
1,1,.006,-.00533,-.00867*
20,1,.006,-.00533,-.00867,-.003,-.00967,0.0*
1,1,.006,-.003,-.00967*
20,1,.006,-.003,-.00967,0.0,-.01,0.0*
1,1,.006,0.0,-.01*
20,1,.006,0.0,-.01,.003,-.00933,0.0*
1,1,.006,.003,-.00933*
20,1,.006,.003,-.00933,.00533,-.008,0.0*
1,1,.006,.00533,-.008*
20,1,.006,.00533,-.008,.007,-.00567,0.0*
1,1,.006,.007,-.00567*
20,1,.006,.007,-.00567,.00733,-.003,0.0*
1,1,.006,.00733,-.003*
20,1,.006,.00733,-.003,.00667,-.00033,0.0*
1,1,.006,.00667,-.00033*
20,1,.006,.00667,-.00033,.005,.00133,0.0*
1,1,.006,.005,.00133*
20,1,.006,.005,.00133,.00267,.00267,0.0*
1,1,.006,.00267,.00267*
20,1,.006,.00267,.00267,.00033,.003,0.0*
1,1,.006,.00033,.003*
20,1,.006,.00033,.003,-.002,.00267,0.0*
1,1,.006,-.002,.00267*
20,1,.006,-.002,.00267,-.005,.00133,0.0*
1,1,.006,-.005,.00133*
20,1,.006,-.005,.00133,-.004,.01,0.0*
1,1,.006,-.004,.01*
20,1,.006,-.004,.01,.005,.01,0.0*
1,1,.006,.005,.01*
%
%ADD21MACRO21*%
%AMMACRO10*
1,1,.006,.05133,.05833*
20,1,.006,.05133,.05833,.03733,.06533,0.0*
1,1,.006,.03733,.06533*
20,1,.006,.03733,.06533,.021,.07,0.0*
1,1,.006,.021,.07*
20,1,.006,.021,.07,.00233,.07,0.0*
1,1,.006,.00233,.07*
20,1,.006,.00233,.07,-.01867,.063,0.0*
1,1,.006,-.01867,.063*
20,1,.006,-.01867,.063,-.035,.05133,0.0*
1,1,.006,-.035,.05133*
20,1,.006,-.035,.05133,-.04667,.03733,0.0*
1,1,.006,-.04667,.03733*
20,1,.006,-.04667,.03733,-.056,.014,0.0*
1,1,.006,-.056,.014*
20,1,.006,-.056,.014,-.05834,-.007,0.0*
1,1,.006,-.05834,-.007*
20,1,.006,-.05834,-.007,-.05367,-.028,0.0*
1,1,.006,-.05367,-.028*
20,1,.006,-.05367,-.028,-.04667,-.042,0.0*
1,1,.006,-.04667,-.042*
20,1,.006,-.04667,-.042,-.03267,-.056,0.0*
1,1,.006,-.03267,-.056*
20,1,.006,-.03267,-.056,-.01633,-.06533,0.0*
1,1,.006,-.01633,-.06533*
20,1,.006,-.01633,-.06533,0.0,-.07,0.0*
1,1,.006,0.0,-.07*
20,1,.006,0.0,-.07,.01633,-.07,0.0*
1,1,.006,.01633,-.07*
20,1,.006,.01633,-.07,.03267,-.06533,0.0*
1,1,.006,.03267,-.06533*
20,1,.006,.03267,-.06533,.04667,-.05834,0.0*
1,1,.006,.04667,-.05834*
20,1,.006,.04667,-.05834,.05834,-.049,0.0*
1,1,.006,.05834,-.049*
%
%ADD10MACRO10*%
%AMMACRO22*
1,1,.006,.004,0.0*
20,1,.006,.004,0.0,-.004,0.0,0.0*
1,1,.006,-.004,0.0*
1,1,.006,0.0,.004*
20,1,.006,0.0,.004,0.0,-.004,0.0*
1,1,.006,0.0,-.004*
1,1,.006,.002,0.0*
20,1,.006,.002,0.0,.002,.004,0.0*
1,1,.006,.002,.004*
20,1,.006,.002,.004,.0012,.0032,0.0*
1,1,.006,.0012,.0032*
1,1,.006,.0012,0.0*
20,1,.006,.0012,0.0,.0028,0.0,0.0*
1,1,.006,.0028,0.0*
%
%ADD22MACRO22*%
%AMMACRO24*
1,1,.006,.022,0.0*
20,1,.006,.022,0.0,0.0,-.022,0.0*
1,1,.006,0.0,-.022*
20,1,.006,0.0,-.022,-.022,0.0,0.0*
1,1,.006,-.022,0.0*
20,1,.006,-.022,0.0,0.0,.022,0.0*
1,1,.006,0.0,.022*
20,1,.006,0.0,.022,.022,0.0,0.0*
1,1,.006,.022,0.0*
1,1,.006,-.00697,-.00183*
20,1,.006,-.00697,-.00183,-.0044,.00073,0.0*
1,1,.006,-.0044,.00073*
20,1,.006,-.0044,.00073,-.0022,.0022,0.0*
1,1,.006,-.0022,.0022*
20,1,.006,-.0022,.0022,.00073,.00293,0.0*
1,1,.006,.00073,.00293*
20,1,.006,.00073,.00293,.0033,.0022,0.0*
1,1,.006,.0033,.0022*
20,1,.006,.0033,.0022,.00513,.00073,0.0*
1,1,.006,.00513,.00073*
20,1,.006,.00513,.00073,.0066,-.00147,0.0*
1,1,.006,.0066,-.00147*
20,1,.006,.0066,-.00147,.00697,-.00403,0.0*
1,1,.006,.00697,-.00403*
20,1,.006,.00697,-.00403,.0066,-.00623,0.0*
1,1,.006,.0066,-.00623*
20,1,.006,.0066,-.00623,.00513,-.00843,0.0*
1,1,.006,.00513,-.00843*
20,1,.006,.00513,-.00843,.00293,-.01027,0.0*
1,1,.006,.00293,-.01027*
20,1,.006,.00293,-.01027,.00037,-.011,0.0*
1,1,.006,.00037,-.011*
20,1,.006,.00037,-.011,-.00257,-.01027,0.0*
1,1,.006,-.00257,-.01027*
20,1,.006,-.00257,-.01027,-.00513,-.00807,0.0*
1,1,.006,-.00513,-.00807*
20,1,.006,-.00513,-.00807,-.0066,-.00477,0.0*
1,1,.006,-.0066,-.00477*
20,1,.006,-.0066,-.00477,-.00697,-.0011,0.0*
1,1,.006,-.00697,-.0011*
20,1,.006,-.00697,-.0011,-.00623,.00367,0.0*
1,1,.006,-.00623,.00367*
20,1,.006,-.00623,.00367,-.00513,.00623,0.0*
1,1,.006,-.00513,.00623*
20,1,.006,-.00513,.00623,-.0033,.0088,0.0*
1,1,.006,-.0033,.0088*
20,1,.006,-.0033,.0088,-.00073,.01063,0.0*
1,1,.006,-.00073,.01063*
20,1,.006,-.00073,.01063,.00183,.011,0.0*
1,1,.006,.00183,.011*
20,1,.006,.00183,.011,.0044,.01027,0.0*
1,1,.006,.0044,.01027*
20,1,.006,.0044,.01027,.00623,.00843,0.0*
1,1,.006,.00623,.00843*
%
%ADD24MACRO24*%
%AMMACRO14*
1,1,.006,.0168,.0042*
20,1,.006,.0168,.0042,.0252,.0105,0.0*
1,1,.006,.0252,.0105*
20,1,.006,.0252,.0105,.0315,.021,0.0*
1,1,.006,.0315,.021*
20,1,.006,.0315,.021,.0357,.0357,0.0*
1,1,.006,.0357,.0357*
20,1,.006,.0357,.0357,.0315,.0483,0.0*
1,1,.006,.0315,.0483*
20,1,.006,.0315,.0483,.0231,.0567,0.0*
1,1,.006,.0231,.0567*
20,1,.006,.0231,.0567,.0084,.063,0.0*
1,1,.006,.0084,.063*
20,1,.006,.0084,.063,-.0483,.063,0.0*
1,1,.006,-.0483,.063*
20,1,.006,-.0483,.063,-.0483,-.063,0.0*
1,1,.006,-.0483,-.063*
20,1,.006,-.0483,-.063,.021,-.063,0.0*
1,1,.006,.021,-.063*
20,1,.006,.021,-.063,.0357,-.0546,0.0*
1,1,.006,.0357,-.0546*
20,1,.006,.0357,-.0546,.0441,-.042,0.0*
1,1,.006,.0441,-.042*
20,1,.006,.0441,-.042,.0483,-.0273,0.0*
1,1,.006,.0483,-.0273*
20,1,.006,.0483,-.0273,.0441,-.0126,0.0*
1,1,.006,.0441,-.0126*
20,1,.006,.0441,-.0126,.0315,0.0,0.0*
1,1,.006,.0315,0.0*
20,1,.006,.0315,0.0,.0168,.0042,0.0*
1,1,.006,.0168,.0042*
20,1,.006,.0168,.0042,-.0483,.0042,0.0*
1,1,.006,-.0483,.0042*
%
%ADD14MACRO14*%
%AMMACRO19*
1,1,.006,-.04959,-.0595*
20,1,.006,-.04959,-.0595,0.0,.0595,0.0*
1,1,.006,0.0,.0595*
20,1,.006,0.0,.0595,.04959,-.0595,0.0*
1,1,.006,.04959,-.0595*
1,1,.006,.03173,-.01785*
20,1,.006,.03173,-.01785,-.03174,-.01785,0.0*
1,1,.006,-.03174,-.01785*
%
%ADD19MACRO19*%
%AMMACRO18*
1,1,.006,.006,0.0*
20,1,.006,.006,0.0,.003,.005196,0.0*
1,1,.006,.003,.005196*
20,1,.006,.003,.005196,-.003,.005196,0.0*
1,1,.006,-.003,.005196*
20,1,.006,-.003,.005196,-.006,0.0,0.0*
1,1,.006,-.006,0.0*
20,1,.006,-.006,0.0,-.003,-.005196,0.0*
1,1,.006,-.003,-.005196*
20,1,.006,-.003,-.005196,.003,-.005196,0.0*
1,1,.006,.003,-.005196*
20,1,.006,.003,-.005196,.006,0.0,0.0*
1,1,.006,.006,0.0*
1,1,.006,-.0022,-.0018*
20,1,.006,-.0022,-.0018,-.0016,-.0025,0.0*
1,1,.006,-.0016,-.0025*
20,1,.006,-.0016,-.0025,-.0008,-.0029,0.0*
1,1,.006,-.0008,-.0029*
20,1,.006,-.0008,-.0029,.0001,-.003,0.0*
1,1,.006,.0001,-.003*
20,1,.006,.0001,-.003,.0009,-.0029,0.0*
1,1,.006,.0009,-.0029*
20,1,.006,.0009,-.0029,.0017,-.0024,0.0*
1,1,.006,.0017,-.0024*
20,1,.006,.0017,-.0024,.0022,-.0018,0.0*
1,1,.006,.0022,-.0018*
20,1,.006,.0022,-.0018,.0023,-.0012,0.0*
1,1,.006,.0023,-.0012*
20,1,.006,.0023,-.0012,.0021,-.0005,0.0*
1,1,.006,.0021,-.0005*
20,1,.006,.0021,-.0005,.0014,0.0,0.0*
1,1,.006,.0014,0.0*
20,1,.006,.0014,0.0,.0007,.0002,0.0*
1,1,.006,.0007,.0002*
20,1,.006,.0007,.0002,-.0002,.0002,0.0*
1,1,.006,-.0002,.0002*
1,1,.006,.0007,.0002*
20,1,.006,.0007,.0002,.0013,.0005,0.0*
1,1,.006,.0013,.0005*
20,1,.006,.0013,.0005,.0018,.001,0.0*
1,1,.006,.0018,.001*
20,1,.006,.0018,.001,.002,.0016,0.0*
1,1,.006,.002,.0016*
20,1,.006,.002,.0016,.0018,.0022,0.0*
1,1,.006,.0018,.0022*
20,1,.006,.0018,.0022,.0013,.0027,0.0*
1,1,.006,.0013,.0027*
20,1,.006,.0013,.0027,.0004,.003,0.0*
1,1,.006,.0004,.003*
20,1,.006,.0004,.003,-.0005,.0029,0.0*
1,1,.006,-.0005,.0029*
20,1,.006,-.0005,.0029,-.0014,.0025,0.0*
1,1,.006,-.0014,.0025*
%
%ADD18MACRO18*%
%AMMACRO23*
1,1,.006,-.0315,.063*
20,1,.006,-.0315,.063,.0315,.063,0.0*
1,1,.006,.0315,.063*
20,1,.006,.0315,.063,.04244,.062043,0.0*
1,1,.006,.04244,.062043*
20,1,.006,.04244,.062043,.053047,.059201,0.0*
1,1,.006,.053047,.059201*
20,1,.006,.053047,.059201,.063,.05456,0.0*
1,1,.006,.063,.05456*
20,1,.006,.063,.05456,.071996,.048261,0.0*
1,1,.006,.071996,.048261*
20,1,.006,.071996,.048261,.079761,.040496,0.0*
1,1,.006,.079761,.040496*
20,1,.006,.079761,.040496,.08606,.0315,0.0*
1,1,.006,.08606,.0315*
20,1,.006,.08606,.0315,.090701,.021547,0.0*
1,1,.006,.090701,.021547*
20,1,.006,.090701,.021547,.093543,.01094,0.0*
1,1,.006,.093543,.01094*
20,1,.006,.093543,.01094,.0945,0.0,0.0*
1,1,.006,.0945,0.0*
20,1,.006,.0945,0.0,.093543,-.01094,0.0*
1,1,.006,.093543,-.01094*
20,1,.006,.093543,-.01094,.090701,-.021547,0.0*
1,1,.006,.090701,-.021547*
20,1,.006,.090701,-.021547,.08606,-.0315,0.0*
1,1,.006,.08606,-.0315*
20,1,.006,.08606,-.0315,.079761,-.040496,0.0*
1,1,.006,.079761,-.040496*
20,1,.006,.079761,-.040496,.071996,-.048261,0.0*
1,1,.006,.071996,-.048261*
20,1,.006,.071996,-.048261,.063,-.05456,0.0*
1,1,.006,.063,-.05456*
20,1,.006,.063,-.05456,.053047,-.059201,0.0*
1,1,.006,.053047,-.059201*
20,1,.006,.053047,-.059201,.04244,-.062043,0.0*
1,1,.006,.04244,-.062043*
20,1,.006,.04244,-.062043,.0315,-.063,0.0*
1,1,.006,.0315,-.063*
20,1,.006,.0315,-.063,-.0315,-.063,0.0*
1,1,.006,-.0315,-.063*
20,1,.006,-.0315,-.063,-.04244,-.062043,0.0*
1,1,.006,-.04244,-.062043*
20,1,.006,-.04244,-.062043,-.053047,-.059201,0.0*
1,1,.006,-.053047,-.059201*
20,1,.006,-.053047,-.059201,-.063,-.05456,0.0*
1,1,.006,-.063,-.05456*
20,1,.006,-.063,-.05456,-.071996,-.048261,0.0*
1,1,.006,-.071996,-.048261*
20,1,.006,-.071996,-.048261,-.079761,-.040496,0.0*
1,1,.006,-.079761,-.040496*
20,1,.006,-.079761,-.040496,-.08606,-.0315,0.0*
1,1,.006,-.08606,-.0315*
20,1,.006,-.08606,-.0315,-.090701,-.021547,0.0*
1,1,.006,-.090701,-.021547*
20,1,.006,-.090701,-.021547,-.093543,-.01094,0.0*
1,1,.006,-.093543,-.01094*
20,1,.006,-.093543,-.01094,-.0945,0.0,0.0*
1,1,.006,-.0945,0.0*
20,1,.006,-.0945,0.0,-.093543,.01094,0.0*
1,1,.006,-.093543,.01094*
20,1,.006,-.093543,.01094,-.090701,.021547,0.0*
1,1,.006,-.090701,.021547*
20,1,.006,-.090701,.021547,-.08606,.0315,0.0*
1,1,.006,-.08606,.0315*
20,1,.006,-.08606,.0315,-.079761,.040496,0.0*
1,1,.006,-.079761,.040496*
20,1,.006,-.079761,.040496,-.071996,.048261,0.0*
1,1,.006,-.071996,.048261*
20,1,.006,-.071996,.048261,-.063,.05456,0.0*
1,1,.006,-.063,.05456*
20,1,.006,-.063,.05456,-.053047,.059201,0.0*
1,1,.006,-.053047,.059201*
20,1,.006,-.053047,.059201,-.04244,.062043,0.0*
1,1,.006,-.04244,.062043*
20,1,.006,-.04244,.062043,-.0315,.063,0.0*
1,1,.006,-.0315,.063*
1,1,.006,-.0315,-.0315*
20,1,.006,-.0315,-.0315,-.0399,-.03045,0.0*
1,1,.006,-.0399,-.03045*
20,1,.006,-.0399,-.03045,-.04725,-.02625,0.0*
1,1,.006,-.04725,-.02625*
20,1,.006,-.04725,-.02625,-.05355,-.01995,0.0*
1,1,.006,-.05355,-.01995*
20,1,.006,-.05355,-.01995,-.05775,-.0126,0.0*
1,1,.006,-.05775,-.0126*
20,1,.006,-.05775,-.0126,-.05985,-.0042,0.0*
1,1,.006,-.05985,-.0042*
20,1,.006,-.05985,-.0042,-.05985,.0042,0.0*
1,1,.006,-.05985,.0042*
20,1,.006,-.05985,.0042,-.05775,.0126,0.0*
1,1,.006,-.05775,.0126*
20,1,.006,-.05775,.0126,-.05355,.01995,0.0*
1,1,.006,-.05355,.01995*
20,1,.006,-.05355,.01995,-.04725,.02625,0.0*
1,1,.006,-.04725,.02625*
20,1,.006,-.04725,.02625,-.0399,.03045,0.0*
1,1,.006,-.0399,.03045*
20,1,.006,-.0399,.03045,-.0315,.0315,0.0*
1,1,.006,-.0315,.0315*
20,1,.006,-.0315,.0315,-.0231,.03045,0.0*
1,1,.006,-.0231,.03045*
20,1,.006,-.0231,.03045,-.01575,.02625,0.0*
1,1,.006,-.01575,.02625*
20,1,.006,-.01575,.02625,-.00945,.01995,0.0*
1,1,.006,-.00945,.01995*
20,1,.006,-.00945,.01995,-.00525,.0126,0.0*
1,1,.006,-.00525,.0126*
20,1,.006,-.00525,.0126,-.00315,.0042,0.0*
1,1,.006,-.00315,.0042*
20,1,.006,-.00315,.0042,-.00315,-.0042,0.0*
1,1,.006,-.00315,-.0042*
20,1,.006,-.00315,-.0042,-.00525,-.0126,0.0*
1,1,.006,-.00525,-.0126*
20,1,.006,-.00525,-.0126,-.00945,-.01995,0.0*
1,1,.006,-.00945,-.01995*
20,1,.006,-.00945,-.01995,-.01575,-.02625,0.0*
1,1,.006,-.01575,-.02625*
20,1,.006,-.01575,-.02625,-.0231,-.03045,0.0*
1,1,.006,-.0231,-.03045*
20,1,.006,-.0231,-.03045,-.0315,-.0315,0.0*
1,1,.006,-.0315,-.0315*
1,1,.006,.00526,-.0315*
20,1,.006,.00526,-.0315,.03151,.0315,0.0*
1,1,.006,.03151,.0315*
20,1,.006,.03151,.0315,.05776,-.0315,0.0*
1,1,.006,.05776,-.0315*
1,1,.006,.04831,-.00945*
20,1,.006,.04831,-.00945,.01471,-.00945,0.0*
1,1,.006,.01471,-.00945*
%
%ADD23MACRO23*%
%AMMACRO17*
1,1,.006,0.0,.02*
20,1,.006,0.0,.02,.02,-.02,0.0*
1,1,.006,.02,-.02*
20,1,.006,.02,-.02,-.02,-.02,0.0*
1,1,.006,-.02,-.02*
20,1,.006,-.02,-.02,0.0,.02,0.0*
1,1,.006,0.0,.02*
1,1,.006,-.00067,-.01*
20,1,.006,-.00067,-.01,0.0,-.00567,0.0*
1,1,.006,0.0,-.00567*
20,1,.006,0.0,-.00567,.001,-.002,0.0*
1,1,.006,.001,-.002*
20,1,.006,.001,-.002,.00233,.00133,0.0*
1,1,.006,.00233,.00133*
20,1,.006,.00233,.00133,.004,.005,0.0*
1,1,.006,.004,.005*
20,1,.006,.004,.005,.00667,.01,0.0*
1,1,.006,.00667,.01*
20,1,.006,.00667,.01,-.00667,.01,0.0*
1,1,.006,-.00667,.01*
%
%ADD17MACRO17*%
%AMMACRO16*
1,1,.006,-.0055,.0165*
20,1,.006,-.0055,.0165,.0055,.0165,0.0*
1,1,.006,.0055,.0165*
20,1,.006,.0055,.0165,.008365,.016249,0.0*
1,1,.006,.008365,.016249*
20,1,.006,.008365,.016249,.011143,.015505,0.0*
1,1,.006,.011143,.015505*
20,1,.006,.011143,.015505,.01375,.014289,0.0*
1,1,.006,.01375,.014289*
20,1,.006,.01375,.014289,.016106,.01264,0.0*
1,1,.006,.016106,.01264*
20,1,.006,.016106,.01264,.01814,.010606,0.0*
1,1,.006,.01814,.010606*
20,1,.006,.01814,.010606,.019789,.00825,0.0*
1,1,.006,.019789,.00825*
20,1,.006,.019789,.00825,.021005,.005643,0.0*
1,1,.006,.021005,.005643*
20,1,.006,.021005,.005643,.021749,.002865,0.0*
1,1,.006,.021749,.002865*
20,1,.006,.021749,.002865,.022,0.0,0.0*
1,1,.006,.022,0.0*
20,1,.006,.022,0.0,.021749,-.002865,0.0*
1,1,.006,.021749,-.002865*
20,1,.006,.021749,-.002865,.021005,-.005643,0.0*
1,1,.006,.021005,-.005643*
20,1,.006,.021005,-.005643,.019789,-.00825,0.0*
1,1,.006,.019789,-.00825*
20,1,.006,.019789,-.00825,.01814,-.010606,0.0*
1,1,.006,.01814,-.010606*
20,1,.006,.01814,-.010606,.016106,-.01264,0.0*
1,1,.006,.016106,-.01264*
20,1,.006,.016106,-.01264,.01375,-.014289,0.0*
1,1,.006,.01375,-.014289*
20,1,.006,.01375,-.014289,.011143,-.015505,0.0*
1,1,.006,.011143,-.015505*
20,1,.006,.011143,-.015505,.008365,-.016249,0.0*
1,1,.006,.008365,-.016249*
20,1,.006,.008365,-.016249,.0055,-.0165,0.0*
1,1,.006,.0055,-.0165*
20,1,.006,.0055,-.0165,-.0055,-.0165,0.0*
1,1,.006,-.0055,-.0165*
20,1,.006,-.0055,-.0165,-.008365,-.016249,0.0*
1,1,.006,-.008365,-.016249*
20,1,.006,-.008365,-.016249,-.011143,-.015505,0.0*
1,1,.006,-.011143,-.015505*
20,1,.006,-.011143,-.015505,-.01375,-.014289,0.0*
1,1,.006,-.01375,-.014289*
20,1,.006,-.01375,-.014289,-.016106,-.01264,0.0*
1,1,.006,-.016106,-.01264*
20,1,.006,-.016106,-.01264,-.01814,-.010606,0.0*
1,1,.006,-.01814,-.010606*
20,1,.006,-.01814,-.010606,-.019789,-.00825,0.0*
1,1,.006,-.019789,-.00825*
20,1,.006,-.019789,-.00825,-.021005,-.005643,0.0*
1,1,.006,-.021005,-.005643*
20,1,.006,-.021005,-.005643,-.021749,-.002865,0.0*
1,1,.006,-.021749,-.002865*
20,1,.006,-.021749,-.002865,-.022,0.0,0.0*
1,1,.006,-.022,0.0*
20,1,.006,-.022,0.0,-.021749,.002865,0.0*
1,1,.006,-.021749,.002865*
20,1,.006,-.021749,.002865,-.021005,.005643,0.0*
1,1,.006,-.021005,.005643*
20,1,.006,-.021005,.005643,-.019789,.00825,0.0*
1,1,.006,-.019789,.00825*
20,1,.006,-.019789,.00825,-.01814,.010606,0.0*
1,1,.006,-.01814,.010606*
20,1,.006,-.01814,.010606,-.016106,.01264,0.0*
1,1,.006,-.016106,.01264*
20,1,.006,-.016106,.01264,-.01375,.014289,0.0*
1,1,.006,-.01375,.014289*
20,1,.006,-.01375,.014289,-.011143,.015505,0.0*
1,1,.006,-.011143,.015505*
20,1,.006,-.011143,.015505,-.008365,.016249,0.0*
1,1,.006,-.008365,.016249*
20,1,.006,-.008365,.016249,-.0055,.0165,0.0*
1,1,.006,-.0055,.0165*
1,1,.006,0.0,-.00825*
20,1,.006,0.0,-.00825,.00192,-.00798,0.0*
1,1,.006,.00192,-.00798*
20,1,.006,.00192,-.00798,.00412,-.00715,0.0*
1,1,.006,.00412,-.00715*
20,1,.006,.00412,-.00715,.0055,-.00578,0.0*
1,1,.006,.0055,-.00578*
20,1,.006,.0055,-.00578,.00605,-.00385,0.0*
1,1,.006,.00605,-.00385*
20,1,.006,.00605,-.00385,.0055,-.00193,0.0*
1,1,.006,.0055,-.00193*
20,1,.006,.0055,-.00193,.00385,-.00028,0.0*
1,1,.006,.00385,-.00028*
20,1,.006,.00385,-.00028,.00137,.00055,0.0*
1,1,.006,.00137,.00055*
20,1,.006,.00137,.00055,-.00137,.00055,0.0*
1,1,.006,-.00137,.00055*
20,1,.006,-.00137,.00055,-.00303,.0011,0.0*
1,1,.006,-.00303,.0011*
20,1,.006,-.00303,.0011,-.0044,.00247,0.0*
1,1,.006,-.0044,.00247*
20,1,.006,-.0044,.00247,-.00495,.0044,0.0*
1,1,.006,-.00495,.0044*
20,1,.006,-.00495,.0044,-.00412,.00632,0.0*
1,1,.006,-.00412,.00632*
20,1,.006,-.00412,.00632,-.0022,.0077,0.0*
1,1,.006,-.0022,.0077*
20,1,.006,-.0022,.0077,0.0,.00825,0.0*
1,1,.006,0.0,.00825*
20,1,.006,0.0,.00825,.0022,.0077,0.0*
1,1,.006,.0022,.0077*
20,1,.006,.0022,.0077,.00412,.00632,0.0*
1,1,.006,.00412,.00632*
20,1,.006,.00412,.00632,.00495,.0044,0.0*
1,1,.006,.00495,.0044*
20,1,.006,.00495,.0044,.0044,.00247,0.0*
1,1,.006,.0044,.00247*
20,1,.006,.0044,.00247,.00303,.0011,0.0*
1,1,.006,.00303,.0011*
20,1,.006,.00303,.0011,.00137,.00055,0.0*
1,1,.006,.00137,.00055*
20,1,.006,.00137,.00055,-.00137,.00055,0.0*
1,1,.006,-.00137,.00055*
20,1,.006,-.00137,.00055,-.00385,-.00028,0.0*
1,1,.006,-.00385,-.00028*
20,1,.006,-.00385,-.00028,-.0055,-.00193,0.0*
1,1,.006,-.0055,-.00193*
20,1,.006,-.0055,-.00193,-.00605,-.00385,0.0*
1,1,.006,-.00605,-.00385*
20,1,.006,-.00605,-.00385,-.0055,-.00578,0.0*
1,1,.006,-.0055,-.00578*
20,1,.006,-.0055,-.00578,-.00412,-.00715,0.0*
1,1,.006,-.00412,-.00715*
20,1,.006,-.00412,-.00715,-.00192,-.00798,0.0*
1,1,.006,-.00192,-.00798*
20,1,.006,-.00192,-.00798,0.0,-.00825,0.0*
1,1,.006,0.0,-.00825*
%
%ADD16MACRO16*%
%AMMACRO12*
1,1,.006,0.0,.008*
20,1,.006,0.0,.008,-.006928,.004,0.0*
1,1,.006,-.006928,.004*
20,1,.006,-.006928,.004,-.006928,-.004,0.0*
1,1,.006,-.006928,-.004*
20,1,.006,-.006928,-.004,0.0,-.008,0.0*
1,1,.006,0.0,-.008*
20,1,.006,0.0,-.008,.006928,-.004,0.0*
1,1,.006,.006928,-.004*
20,1,.006,.006928,-.004,.006928,.004,0.0*
1,1,.006,.006928,.004*
20,1,.006,.006928,.004,0.0,.008,0.0*
1,1,.006,0.0,.008*
1,1,.006,.0016,-.004*
20,1,.006,.0016,-.004,.0016,.004,0.0*
1,1,.006,.0016,.004*
20,1,.006,.0016,.004,-.00333,-.00173,0.0*
1,1,.006,-.00333,-.00173*
20,1,.006,-.00333,-.00173,.00333,-.00173,0.0*
1,1,.006,.00333,-.00173*
%
%ADD12MACRO12*%
%AMMACRO11*
1,1,.006,.043,0.0*
20,1,.006,.043,0.0,.042347,-.007467,0.0*
1,1,.006,.042347,-.007467*
20,1,.006,.042347,-.007467,.040407,-.014707,0.0*
1,1,.006,.040407,-.014707*
20,1,.006,.040407,-.014707,.037239,-.0215,0.0*
1,1,.006,.037239,-.0215*
20,1,.006,.037239,-.0215,.03294,-.02764,0.0*
1,1,.006,.03294,-.02764*
20,1,.006,.03294,-.02764,.02764,-.03294,0.0*
1,1,.006,.02764,-.03294*
20,1,.006,.02764,-.03294,.0215,-.037239,0.0*
1,1,.006,.0215,-.037239*
20,1,.006,.0215,-.037239,.014707,-.040407,0.0*
1,1,.006,.014707,-.040407*
20,1,.006,.014707,-.040407,.007467,-.042347,0.0*
1,1,.006,.007467,-.042347*
20,1,.006,.007467,-.042347,0.0,-.043,0.0*
1,1,.006,0.0,-.043*
20,1,.006,0.0,-.043,-.007467,-.042347,0.0*
1,1,.006,-.007467,-.042347*
20,1,.006,-.007467,-.042347,-.014707,-.040407,0.0*
1,1,.006,-.014707,-.040407*
20,1,.006,-.014707,-.040407,-.0215,-.037239,0.0*
1,1,.006,-.0215,-.037239*
20,1,.006,-.0215,-.037239,-.02764,-.03294,0.0*
1,1,.006,-.02764,-.03294*
20,1,.006,-.02764,-.03294,-.03294,-.02764,0.0*
1,1,.006,-.03294,-.02764*
20,1,.006,-.03294,-.02764,-.037239,-.0215,0.0*
1,1,.006,-.037239,-.0215*
20,1,.006,-.037239,-.0215,-.040407,-.014707,0.0*
1,1,.006,-.040407,-.014707*
20,1,.006,-.040407,-.014707,-.042347,-.007467,0.0*
1,1,.006,-.042347,-.007467*
20,1,.006,-.042347,-.007467,-.043,0.0,0.0*
1,1,.006,-.043,0.0*
20,1,.006,-.043,0.0,-.042347,.007467,0.0*
1,1,.006,-.042347,.007467*
20,1,.006,-.042347,.007467,-.040407,.014707,0.0*
1,1,.006,-.040407,.014707*
20,1,.006,-.040407,.014707,-.037239,.0215,0.0*
1,1,.006,-.037239,.0215*
20,1,.006,-.037239,.0215,-.03294,.02764,0.0*
1,1,.006,-.03294,.02764*
20,1,.006,-.03294,.02764,-.02764,.03294,0.0*
1,1,.006,-.02764,.03294*
20,1,.006,-.02764,.03294,-.0215,.037239,0.0*
1,1,.006,-.0215,.037239*
20,1,.006,-.0215,.037239,-.014707,.040407,0.0*
1,1,.006,-.014707,.040407*
20,1,.006,-.014707,.040407,-.007467,.042347,0.0*
1,1,.006,-.007467,.042347*
20,1,.006,-.007467,.042347,0.0,.043,0.0*
1,1,.006,0.0,.043*
20,1,.006,0.0,.043,.007467,.042347,0.0*
1,1,.006,.007467,.042347*
20,1,.006,.007467,.042347,.014707,.040407,0.0*
1,1,.006,.014707,.040407*
20,1,.006,.014707,.040407,.0215,.037239,0.0*
1,1,.006,.0215,.037239*
20,1,.006,.0215,.037239,.02764,.03294,0.0*
1,1,.006,.02764,.03294*
20,1,.006,.02764,.03294,.03294,.02764,0.0*
1,1,.006,.03294,.02764*
20,1,.006,.03294,.02764,.037239,.0215,0.0*
1,1,.006,.037239,.0215*
20,1,.006,.037239,.0215,.040407,.014707,0.0*
1,1,.006,.040407,.014707*
20,1,.006,.040407,.014707,.042347,.007467,0.0*
1,1,.006,.042347,.007467*
20,1,.006,.042347,.007467,.043,0.0,0.0*
1,1,.006,.043,0.0*
1,1,.006,-.0215,-.0215*
20,1,.006,-.0215,-.0215,-.0215,.0215,0.0*
1,1,.006,-.0215,.0215*
20,1,.006,-.0215,.0215,-.0301,.0129,0.0*
1,1,.006,-.0301,.0129*
1,1,.006,-.0301,-.0215*
20,1,.006,-.0301,-.0215,-.0129,-.0215,0.0*
1,1,.006,-.0129,-.0215*
1,1,.006,.02151,-.0215*
20,1,.006,.02151,-.0215,.02151,.0215,0.0*
1,1,.006,.02151,.0215*
20,1,.006,.02151,.0215,.01291,.0129,0.0*
1,1,.006,.01291,.0129*
1,1,.006,.01291,-.0215*
20,1,.006,.01291,-.0215,.03011,-.0215,0.0*
1,1,.006,.03011,-.0215*
%
%ADD11MACRO11*%
%AMMACRO20*
1,1,.006,-.023625,.007875*
20,1,.006,-.023625,.007875,-.023266,.011977,0.0*
1,1,.006,-.023266,.011977*
20,1,.006,-.023266,.011977,-.0222,.015955,0.0*
1,1,.006,-.0222,.015955*
20,1,.006,-.0222,.015955,-.02046,.019687,0.0*
1,1,.006,-.02046,.019687*
20,1,.006,-.02046,.019687,-.018098,.023061,0.0*
1,1,.006,-.018098,.023061*
20,1,.006,-.018098,.023061,-.015186,.025973,0.0*
1,1,.006,-.015186,.025973*
20,1,.006,-.015186,.025973,-.011813,.028335,0.0*
1,1,.006,-.011813,.028335*
20,1,.006,-.011813,.028335,-.00808,.030075,0.0*
1,1,.006,-.00808,.030075*
20,1,.006,-.00808,.030075,-.004102,.031141,0.0*
1,1,.006,-.004102,.031141*
20,1,.006,-.004102,.031141,0.0,.0315,0.0*
1,1,.006,0.0,.0315*
20,1,.006,0.0,.0315,.004102,.031141,0.0*
1,1,.006,.004102,.031141*
20,1,.006,.004102,.031141,.00808,.030075,0.0*
1,1,.006,.00808,.030075*
20,1,.006,.00808,.030075,.011812,.028335,0.0*
1,1,.006,.011812,.028335*
20,1,.006,.011812,.028335,.015186,.025973,0.0*
1,1,.006,.015186,.025973*
20,1,.006,.015186,.025973,.018098,.023061,0.0*
1,1,.006,.018098,.023061*
20,1,.006,.018098,.023061,.02046,.019688,0.0*
1,1,.006,.02046,.019688*
20,1,.006,.02046,.019688,.0222,.015955,0.0*
1,1,.006,.0222,.015955*
20,1,.006,.0222,.015955,.023266,.011977,0.0*
1,1,.006,.023266,.011977*
20,1,.006,.023266,.011977,.023625,.007875,0.0*
1,1,.006,.023625,.007875*
20,1,.006,.023625,.007875,.023625,-.007875,0.0*
1,1,.006,.023625,-.007875*
20,1,.006,.023625,-.007875,.023266,-.011977,0.0*
1,1,.006,.023266,-.011977*
20,1,.006,.023266,-.011977,.0222,-.015955,0.0*
1,1,.006,.0222,-.015955*
20,1,.006,.0222,-.015955,.02046,-.019687,0.0*
1,1,.006,.02046,-.019687*
20,1,.006,.02046,-.019687,.018098,-.023061,0.0*
1,1,.006,.018098,-.023061*
20,1,.006,.018098,-.023061,.015186,-.025973,0.0*
1,1,.006,.015186,-.025973*
20,1,.006,.015186,-.025973,.011813,-.028335,0.0*
1,1,.006,.011813,-.028335*
20,1,.006,.011813,-.028335,.00808,-.030075,0.0*
1,1,.006,.00808,-.030075*
20,1,.006,.00808,-.030075,.004102,-.031141,0.0*
1,1,.006,.004102,-.031141*
20,1,.006,.004102,-.031141,0.0,-.0315,0.0*
1,1,.006,0.0,-.0315*
20,1,.006,0.0,-.0315,-.004102,-.031141,0.0*
1,1,.006,-.004102,-.031141*
20,1,.006,-.004102,-.031141,-.00808,-.030075,0.0*
1,1,.006,-.00808,-.030075*
20,1,.006,-.00808,-.030075,-.011812,-.028335,0.0*
1,1,.006,-.011812,-.028335*
20,1,.006,-.011812,-.028335,-.015186,-.025973,0.0*
1,1,.006,-.015186,-.025973*
20,1,.006,-.015186,-.025973,-.018098,-.023061,0.0*
1,1,.006,-.018098,-.023061*
20,1,.006,-.018098,-.023061,-.02046,-.019688,0.0*
1,1,.006,-.02046,-.019688*
20,1,.006,-.02046,-.019688,-.0222,-.015955,0.0*
1,1,.006,-.0222,-.015955*
20,1,.006,-.0222,-.015955,-.023266,-.011977,0.0*
1,1,.006,-.023266,-.011977*
20,1,.006,-.023266,-.011977,-.023625,-.007875,0.0*
1,1,.006,-.023625,-.007875*
20,1,.006,-.023625,-.007875,-.023625,.007875,0.0*
1,1,.006,-.023625,.007875*
1,1,.006,-.00669,-.00905*
20,1,.006,-.00669,-.00905,-.00394,-.01102,0.0*
1,1,.006,-.00394,-.01102*
20,1,.006,-.00394,-.01102,-.00079,-.01181,0.0*
1,1,.006,-.00079,-.01181*
20,1,.006,-.00079,-.01181,.00236,-.01102,0.0*
1,1,.006,.00236,-.01102*
20,1,.006,.00236,-.01102,.00512,-.00866,0.0*
1,1,.006,.00512,-.00866*
20,1,.006,.00512,-.00866,.00709,-.00512,0.0*
1,1,.006,.00709,-.00512*
20,1,.006,.00709,-.00512,.00787,-.00157,0.0*
1,1,.006,.00787,-.00157*
20,1,.006,.00787,-.00157,.00787,.00276,0.0*
1,1,.006,.00787,.00276*
20,1,.006,.00787,.00276,.00709,.0063,0.0*
1,1,.006,.00709,.0063*
20,1,.006,.00709,.0063,.00512,.00945,0.0*
1,1,.006,.00512,.00945*
20,1,.006,.00512,.00945,.00276,.01102,0.0*
1,1,.006,.00276,.01102*
20,1,.006,.00276,.01102,0.0,.01181,0.0*
1,1,.006,0.0,.01181*
20,1,.006,0.0,.01181,-.00315,.01102,0.0*
1,1,.006,-.00315,.01102*
20,1,.006,-.00315,.01102,-.00551,.00945,0.0*
1,1,.006,-.00551,.00945*
20,1,.006,-.00551,.00945,-.00709,.00709,0.0*
1,1,.006,-.00709,.00709*
20,1,.006,-.00709,.00709,-.00787,.00394,0.0*
1,1,.006,-.00787,.00394*
20,1,.006,-.00787,.00394,-.00709,.00118,0.0*
1,1,.006,-.00709,.00118*
20,1,.006,-.00709,.00118,-.00512,-.00157,0.0*
1,1,.006,-.00512,-.00157*
20,1,.006,-.00512,-.00157,-.00276,-.00315,0.0*
1,1,.006,-.00276,-.00315*
20,1,.006,-.00276,-.00315,0.0,-.00354,0.0*
1,1,.006,0.0,-.00354*
20,1,.006,0.0,-.00354,.00315,-.00276,0.0*
1,1,.006,.00315,-.00276*
20,1,.006,.00315,-.00276,.00551,-.00079,0.0*
1,1,.006,.00551,-.00079*
20,1,.006,.00551,-.00079,.00787,.00276,0.0*
1,1,.006,.00787,.00276*
%
%ADD20MACRO20*%
%ADD25C,.02*%
%ADD26C,.006*%
G75*
%LPD*%
G75*
G54D10*
X-19686Y15748D03*
Y573228D03*
X846455Y15748D03*
Y573228D03*
X948450Y84950D03*
G54D20*
X235630Y174016D03*
X498425Y22798D03*
D03*
X755512Y262598D03*
D03*
X948450Y225450D03*
G54D11*
X11500Y68500D03*
X12000Y279000D03*
X816000Y280000D03*
X948450Y169250D03*
G54D12*
X14000Y104500D03*
X14400Y98000D03*
X14000Y109500D03*
X15400Y118000D03*
X10900D03*
X13000Y137000D03*
X15500Y122800D03*
X15000Y127500D03*
X11000Y122800D03*
X10500Y127500D03*
X13000Y141500D03*
X13100Y150600D03*
X13000Y146000D03*
X11500Y163700D03*
Y159000D03*
X7000Y163700D03*
Y159000D03*
X14500Y198000D03*
X4500Y228900D03*
X4600Y223100D03*
X4500Y234800D03*
X4400Y245100D03*
Y256700D03*
X5000Y275000D03*
X12600Y266900D03*
X15300Y285800D03*
X4900Y285700D03*
X23400Y81550D03*
X25000Y77300D03*
X33000Y105000D03*
X30200Y145000D03*
Y149200D03*
X34000Y161500D03*
X30300Y157600D03*
X30200Y153400D03*
X25200Y286000D03*
X37500Y105000D03*
X42000D03*
X45500Y118000D03*
X37500Y264000D03*
X63500Y43500D03*
Y57500D03*
Y48000D03*
Y52500D03*
X50500Y160000D03*
X63200Y194900D03*
X68500Y47500D03*
X73500Y48000D03*
X68000Y52500D03*
X76200Y187200D03*
X70900Y193800D03*
X95500Y93500D03*
X94000Y137500D03*
Y133000D03*
X82000Y177500D03*
X86500D03*
X90700Y177050D03*
X92800Y285600D03*
X99500Y91500D03*
Y96000D03*
X104000Y106600D03*
Y92000D03*
Y96500D03*
Y115500D03*
Y111000D03*
X105775Y137349D03*
X103175Y134050D03*
X98500Y137500D03*
X109000Y134050D03*
X98500Y133000D03*
X100000Y267400D03*
X100700Y262900D03*
X97500Y285450D03*
X102000D03*
X106500Y285550D03*
X110700D03*
X119400Y106700D03*
X123800Y102500D03*
X123900Y106700D03*
X119400Y102300D03*
Y115900D03*
Y111200D03*
X123900Y115900D03*
Y111200D03*
X114500Y134050D03*
X113200Y146700D03*
X113100Y151000D03*
X117500Y146950D03*
X119000Y159100D03*
X114700Y158800D03*
X116500Y211200D03*
X122250Y228750D03*
Y233000D03*
Y237300D03*
Y241500D03*
X134100Y96600D03*
X128500Y165000D03*
X133941Y208863D03*
X131003Y205766D03*
X138100Y208100D03*
X129500Y252500D03*
X129000Y268000D03*
X136500Y272500D03*
X158700Y213800D03*
X166500Y241000D03*
X186500Y276500D03*
Y281000D03*
X189000Y87700D03*
X192500Y161900D03*
X192600Y166700D03*
X201200Y164200D03*
X203100Y252900D03*
X191100Y276600D03*
X190900Y280800D03*
X216261Y74846D03*
X212300Y157300D03*
X212600Y161500D03*
X211900Y253000D03*
X207500D03*
X217000Y252900D03*
X217200Y258000D03*
X212400Y281200D03*
X217000Y281000D03*
X212500Y277000D03*
X208000D03*
X226900Y133300D03*
X234525Y239250D03*
X229700Y234700D03*
X225300Y239200D03*
X234525Y243450D03*
X229725D03*
X225300Y243400D03*
X234525Y234800D03*
X225300D03*
X229675Y239000D03*
X233500Y258958D03*
X228000Y259000D03*
X221300Y255400D03*
X240130Y77300D03*
X236400Y95100D03*
X240565Y113365D03*
X249350Y199400D03*
X248300Y213500D03*
X247500Y239250D03*
X243300Y235050D03*
X247500Y243450D03*
X243300D03*
X238900D03*
X243300Y239250D03*
X247500Y235050D03*
X238925Y235000D03*
Y239200D03*
X248000Y259000D03*
X238500D03*
X243000D03*
X258400Y65600D03*
X257000Y213500D03*
X252350Y202350D03*
X252700Y213500D03*
X251700Y239250D03*
Y243450D03*
X252500Y259000D03*
X253000Y267000D03*
X278200Y281350D03*
X294800Y94100D03*
X282686Y281336D03*
X321300Y88200D03*
X339638Y67138D03*
X334500Y266300D03*
X334300Y270500D03*
X335700Y278751D03*
X331500D03*
X353100Y56151D03*
X345089Y73089D03*
X353500Y71900D03*
X357000Y69500D03*
X349300Y83000D03*
X345100D03*
X354200Y76400D03*
X343600Y270500D03*
X371400Y42500D03*
X371500Y47000D03*
X359800Y72700D03*
X362700Y69600D03*
X380000Y38100D03*
X375600Y42500D03*
X380300D03*
X375700Y47000D03*
X380295Y46779D03*
X443800Y246100D03*
X474000Y9000D03*
X467200Y4400D03*
X481500Y8900D03*
X489600Y8800D03*
X497100D03*
X505200Y215000D03*
X496711Y248999D03*
X527000Y225500D03*
X600900Y230200D03*
X598814Y240095D03*
X615700Y230200D03*
X615100Y238900D03*
X630000Y55300D03*
X623400Y230100D03*
X623900Y239600D03*
X646000Y46007D03*
X640000D03*
X640500Y55000D03*
X655133Y55833D03*
X654500Y46107D03*
X653000Y93000D03*
X650726Y125724D03*
X664212Y147993D03*
X659811Y260757D03*
X657500Y258400D03*
X661308Y263698D03*
X655500Y270500D03*
X657787Y264179D03*
X656000Y261400D03*
X655523Y266616D03*
X658667Y267622D03*
X678400Y114500D03*
X668411Y148089D03*
X678500Y141500D03*
X667061Y175239D03*
X693500Y148000D03*
X690000Y159000D03*
X694500D03*
X700089Y91411D03*
X701600Y104900D03*
X701400Y98400D03*
X710200Y201700D03*
X725632Y49600D03*
X721950Y51950D03*
X721200Y65100D03*
X722000Y74500D03*
X717000D03*
X715000Y80300D03*
X714500Y85500D03*
X732000Y63500D03*
X739500Y75500D03*
X753500Y24007D03*
Y20007D03*
Y28507D03*
X755500Y16000D03*
X770500Y13007D03*
X767500Y24007D03*
X760500Y29000D03*
X761000Y16007D03*
X767500Y28507D03*
Y19507D03*
X764200Y44200D03*
X767500Y33207D03*
X759000Y37507D03*
X764500Y54000D03*
X764300Y49200D03*
X769500Y50000D03*
X761000Y58500D03*
X764500Y84800D03*
X760400Y88700D03*
X768100Y89000D03*
X761300Y95700D03*
X763600Y168000D03*
X764000Y188000D03*
Y197500D03*
Y192810D03*
Y202310D03*
X769500Y234500D03*
X769400Y252700D03*
X785500Y8000D03*
X781500Y51000D03*
X777000Y93100D03*
X774300Y102500D03*
X778500D03*
Y107000D03*
X787500Y93000D03*
X783000D03*
X774300Y107000D03*
X783000Y113000D03*
Y118500D03*
Y123000D03*
X785830Y188700D03*
X785400Y202800D03*
X789000Y204979D03*
X789200Y214200D03*
Y209800D03*
X784500Y222500D03*
X789000Y223500D03*
X789200Y218700D03*
X786000Y228000D03*
Y232400D03*
X786200Y236900D03*
X786300Y241500D03*
X785000Y245800D03*
Y250200D03*
Y254900D03*
X792000Y83000D03*
X796500D03*
X792000Y87700D03*
X796500D03*
X799200Y98600D03*
X803100Y106000D03*
X799200Y102800D03*
X799000Y107100D03*
X803500Y116700D03*
Y112500D03*
X799000Y116100D03*
Y111900D03*
X789910Y187679D03*
X794110D03*
X798310Y187779D03*
X793500Y204979D03*
Y223500D03*
X793200Y228400D03*
Y232600D03*
Y237200D03*
Y242400D03*
X793300Y247200D03*
X795300Y260800D03*
X795400Y251700D03*
X795300Y256500D03*
Y265000D03*
X810500Y196500D03*
Y192300D03*
X809200Y209500D03*
Y213700D03*
Y218400D03*
X809100Y228600D03*
Y224400D03*
X808700Y238300D03*
Y234100D03*
Y242900D03*
X809500Y251500D03*
Y257000D03*
X808700Y247100D03*
X810100Y275000D03*
X812035Y271067D03*
X810100Y267339D03*
X812000Y263500D03*
X809700Y285900D03*
X820500Y6500D03*
X821900Y273100D03*
X821600Y285500D03*
X948450Y365950D03*
G54D21*
X276811Y263386D03*
X296811D03*
X457913Y45276D03*
X477913D03*
X948450Y337850D03*
G54D22*
X305900Y121151D03*
X303610Y110800D03*
X309000Y114700D03*
X306700D03*
X311200Y114800D03*
X311410Y118110D03*
X309194Y117700D03*
X306994Y117725D03*
X304149Y128349D03*
X307854Y130539D03*
X309700Y122796D03*
X309500Y132925D03*
X307298Y132697D03*
X307500Y122700D03*
X305050Y151150D03*
X309000Y137600D03*
X311000Y141731D03*
X306961Y153717D03*
X306696Y158610D03*
X309000Y158806D03*
X311242Y158732D03*
X309220Y153698D03*
X305800Y195400D03*
X305290Y187836D03*
X301320Y191060D03*
X303500Y195400D03*
X310500Y195600D03*
X308200D03*
X303480Y189100D03*
X301300Y188700D03*
X309700Y187997D03*
X307500Y188000D03*
X309100Y206800D03*
X317641Y90956D03*
X325081Y100631D03*
X322075Y100650D03*
X323120Y92400D03*
X319520Y92419D03*
X318900Y98000D03*
X317600Y93625D03*
X326162Y91438D03*
X315950Y98650D03*
X315613Y100850D03*
X315400Y110800D03*
X312000Y122600D03*
X320992Y112180D03*
X325300Y112300D03*
X311600Y110800D03*
X322010Y118573D03*
X325350Y114500D03*
X319096Y113300D03*
X319418Y123225D03*
X315451Y123219D03*
X323900Y129900D03*
X322691Y136023D03*
X326313Y122380D03*
X323007Y127672D03*
X320321Y130528D03*
X325418Y127349D03*
X325746Y133702D03*
X312917Y133440D03*
X323300Y147046D03*
X323550Y142104D03*
X319252Y140949D03*
X326322Y138434D03*
X325763Y141958D03*
X319401Y149354D03*
X317698Y152311D03*
X325200Y149319D03*
X319704Y162804D03*
X323000Y153900D03*
X315384Y166733D03*
X324953Y161722D03*
X324200Y157800D03*
X324029Y166384D03*
X326234Y153969D03*
X311417Y153821D03*
X323165Y171937D03*
X324436Y175705D03*
X326399Y169401D03*
X323500Y180063D03*
X311460Y172078D03*
X319942Y180524D03*
X323121Y182913D03*
X326408Y182292D03*
X312829Y181940D03*
X316844Y196010D03*
X319801Y194890D03*
X326550Y191600D03*
X323800Y192150D03*
X323789Y188117D03*
X320029Y184300D03*
X326500Y187900D03*
X311900Y188070D03*
X322256Y198618D03*
X323331Y196696D03*
X319500Y212100D03*
X325642Y202325D03*
X321600Y208700D03*
Y211000D03*
X317200Y213100D03*
X315585Y207787D03*
X324100Y208000D03*
X318700Y207800D03*
X311600Y207600D03*
X325200Y221700D03*
X319400Y216200D03*
X317200Y215300D03*
X313600Y237700D03*
X321400D03*
X316000D03*
X319100D03*
X329300Y87300D03*
X331200Y88600D03*
X330100Y100200D03*
Y98000D03*
X328000Y97100D03*
X334850Y96900D03*
X336750Y93500D03*
X335500Y91600D03*
X336750Y95704D03*
X328000Y92700D03*
X330900Y93400D03*
X333313Y103693D03*
X339500Y102000D03*
X332600Y101400D03*
X329415Y119923D03*
X333601Y120500D03*
X333534Y118040D03*
X333551Y115090D03*
X333434Y106668D03*
X333416Y108899D03*
X330470Y112515D03*
X330910Y115010D03*
X341200Y112569D03*
X338768Y116755D03*
Y119755D03*
X329308Y122386D03*
X338329Y135665D03*
X329031Y125428D03*
X335303Y135178D03*
X339280Y127380D03*
X341309Y135651D03*
X329693Y134428D03*
X331290Y125810D03*
X330870Y130540D03*
X336900Y127600D03*
X333977Y127678D03*
X327854Y130434D03*
X338470Y138177D03*
X335450Y150900D03*
X327963Y142008D03*
X335514Y138220D03*
X338320Y141300D03*
X327390Y149106D03*
X336920Y146130D03*
X329421Y138228D03*
X327696Y146108D03*
X336190Y141970D03*
X330796Y146221D03*
X330163Y142008D03*
X332478Y138255D03*
X341342Y138224D03*
X333750Y145950D03*
X339491Y143163D03*
X329800Y150800D03*
X332000D03*
X330300Y158546D03*
X339784Y161847D03*
X335499Y153846D03*
X327800Y161500D03*
X336900Y161600D03*
X336800Y164434D03*
X341390Y153991D03*
X329161Y153830D03*
X335964Y158512D03*
X333742Y161624D03*
X332185Y153806D03*
X338421Y153802D03*
X334470Y164760D03*
X341400Y156700D03*
X331000Y164500D03*
X330900Y161700D03*
X333000Y158300D03*
X339747Y164478D03*
X341300Y169600D03*
X335400D03*
X339300Y174100D03*
X330821Y177402D03*
X333842Y177224D03*
X332300Y173900D03*
X339875Y177303D03*
X329442Y169463D03*
X327708Y177241D03*
X332353Y169522D03*
X337000Y174102D03*
X327600Y174174D03*
X330027Y174119D03*
X334700Y174100D03*
X336915Y177423D03*
X337863Y180545D03*
X334715Y180900D03*
X330280D03*
X332500D03*
X332100Y185600D03*
X338000Y185700D03*
X335000Y185500D03*
X335400Y196300D03*
X337800Y189200D03*
X326850Y193900D03*
X329972Y196400D03*
Y193559D03*
X333996Y192063D03*
X334707Y189383D03*
X337800Y192200D03*
X338048Y196250D03*
X342029Y196427D03*
X332800Y187700D03*
X326831Y196119D03*
X329313Y188000D03*
X337670Y213520D03*
X335739Y199317D03*
X336500Y204600D03*
X332974Y210874D03*
X338926Y211674D03*
X338967Y209455D03*
X331658Y212660D03*
X329028Y199931D03*
X339800Y207400D03*
X327216Y203902D03*
X330200Y216800D03*
X336000Y219750D03*
X328510Y218320D03*
X327024Y220024D03*
X337307Y217961D03*
X331616Y214860D03*
X337341Y215731D03*
X333036Y231910D03*
X327100Y237100D03*
X328945Y235846D03*
X331142Y233658D03*
X344523Y98477D03*
X344500Y94000D03*
X347230Y100190D03*
X351342Y114158D03*
X346596Y118163D03*
Y115163D03*
X351000Y111700D03*
X355175Y108212D03*
X348076Y108910D03*
X343570Y112561D03*
X346600Y121100D03*
X346495Y130000D03*
X349149Y124141D03*
X351500Y136000D03*
X354333Y125665D03*
X343000Y126200D03*
X343146Y128473D03*
X343000Y124000D03*
X347641Y133479D03*
X342533Y133822D03*
X349600Y126700D03*
X357300Y128600D03*
X355400Y137100D03*
X354300Y128600D03*
X346300Y143000D03*
X342880Y146180D03*
X355447Y146528D03*
X344500Y141700D03*
X348675Y143326D03*
X350800Y138300D03*
X355342Y143424D03*
X348743Y146072D03*
X346000Y146043D03*
X346450Y149120D03*
X348743Y149100D03*
X355460Y149510D03*
X348432Y164844D03*
X346944Y156775D03*
X350550Y153280D03*
X342716Y161593D03*
X344300Y153800D03*
X344090Y156690D03*
X352000Y162000D03*
X348700Y161700D03*
X351600Y164300D03*
X355400Y152900D03*
X355413Y156050D03*
X351700Y167300D03*
X350700Y155600D03*
X345900Y161700D03*
X342188Y183361D03*
X355300Y174600D03*
X347200Y174300D03*
X344165Y169466D03*
X352200Y171800D03*
X350000Y177700D03*
X345562Y178700D03*
X347500Y169500D03*
X351600Y169600D03*
X353302Y182993D03*
X353321Y180128D03*
X342233Y185639D03*
X356900Y186100D03*
X349600Y194800D03*
X342760Y187810D03*
X342339Y192225D03*
X342342Y190024D03*
X349100Y191900D03*
X353625Y195045D03*
Y192045D03*
X356600Y195700D03*
X356700Y193300D03*
X345503Y193474D03*
X345500Y190500D03*
X349100Y189700D03*
X353342Y186124D03*
X349751Y187241D03*
X356800Y191000D03*
X345500Y184500D03*
X345631Y187420D03*
X351950Y214800D03*
X346500Y208350D03*
X345500Y213000D03*
X353594Y210707D03*
X347593Y210277D03*
X353385Y212898D03*
X345837Y199887D03*
X350409Y199755D03*
X353792Y208466D03*
X354700Y199900D03*
X343242Y213690D03*
X347664Y212476D03*
X355860Y216690D03*
X345300Y216700D03*
X343198Y215910D03*
X371900Y85400D03*
X364800Y91200D03*
X368600Y90700D03*
X361200Y90200D03*
X371900Y89000D03*
X371950Y92500D03*
X364874Y98250D03*
X362803Y106035D03*
X357900Y99200D03*
X368600Y97500D03*
X357721Y91779D03*
X361200Y97500D03*
X368600Y94100D03*
X365000Y94700D03*
X357721Y95100D03*
X360900Y94200D03*
X361141Y104099D03*
X365316Y108130D03*
X372700Y119663D03*
X370100Y119563D03*
X370000Y116563D03*
X369997Y113706D03*
X368721Y108528D03*
X359942Y110924D03*
X365721Y115528D03*
X358000Y115500D03*
X366400Y112200D03*
X364600Y137063D03*
X367221Y125428D03*
X370000Y122563D03*
X362111Y127142D03*
X362120Y124153D03*
X359421Y127128D03*
Y124008D03*
X372821Y125628D03*
X370121Y125528D03*
X367321Y122528D03*
X368026Y137118D03*
X364700Y134000D03*
X367992Y133982D03*
X367121Y128628D03*
X362111Y130128D03*
X358500Y137000D03*
X371176Y136890D03*
X359300Y130000D03*
X367900Y152550D03*
X368000Y146500D03*
X361700Y143300D03*
X364886Y140268D03*
X368026D03*
Y143418D03*
X364621Y143328D03*
X361726Y140268D03*
X361700Y146549D03*
X361500Y149500D03*
X364700Y152713D03*
X368026Y149718D03*
X368100Y165300D03*
X364600D03*
X367950Y159200D03*
X371157Y162320D03*
X371176Y158940D03*
X358477Y159300D03*
X361600Y159250D03*
X368100Y162200D03*
X358342Y165324D03*
X358576Y162090D03*
X358500Y155700D03*
X371100Y168700D03*
X364600Y174800D03*
X361500Y175000D03*
Y168500D03*
X368000D03*
X367906Y171458D03*
X364600Y171600D03*
X364607Y177103D03*
X370900Y171700D03*
X361200Y178500D03*
X361292Y181409D03*
X372400Y179100D03*
X369021Y180128D03*
X372600Y181400D03*
X361400Y187600D03*
X368455Y196455D03*
X371299Y196008D03*
X364792Y188743D03*
X364600Y186138D03*
X364895Y190941D03*
X369106Y191903D03*
X369200Y189100D03*
X361257Y193524D03*
Y190700D03*
X364947Y193141D03*
X361300Y184500D03*
X359222Y197700D03*
X369009Y186191D03*
X372700Y213700D03*
X369450Y212040D03*
X359750Y208390D03*
X359910Y214100D03*
X358498Y210220D03*
X358382Y212427D03*
X371100Y199500D03*
X365250Y208600D03*
X372800Y221600D03*
X369580Y218800D03*
Y215400D03*
X357966Y217516D03*
X359827Y216341D03*
X383350Y83350D03*
X383450Y90500D03*
X387200D03*
X387100Y83500D03*
X375800D03*
Y90500D03*
X379500Y83302D03*
Y90600D03*
X375800Y87000D03*
X383450Y86900D03*
X387200D03*
X379500D03*
X379526Y106396D03*
X381950Y100950D03*
X381600Y119900D03*
X381900Y113000D03*
X382596Y108600D03*
X385600Y116500D03*
X385200Y113137D03*
X385721Y119528D03*
X381550Y117400D03*
X377800Y112063D03*
X377818Y115008D03*
X386561Y108812D03*
X377713Y121061D03*
X385479Y125569D03*
X381500Y123200D03*
X381600Y126427D03*
X385523Y122532D03*
X385750Y128517D03*
X386708Y137118D03*
X383567Y137096D03*
X377800Y124163D03*
X380475Y137016D03*
X380400Y133928D03*
X380443Y130102D03*
X374200Y136994D03*
X387000Y143280D03*
X380398Y146568D03*
X383548D03*
X380398Y143418D03*
X383395Y143306D03*
X374200Y140144D03*
Y143294D03*
X380400Y152700D03*
X383575Y149603D03*
X380522Y149564D03*
X386853Y149640D03*
X377476Y149688D03*
X374200Y149494D03*
X374100Y159150D03*
X386800Y165300D03*
X380398Y165240D03*
X383781Y165235D03*
X386777Y162155D03*
X387000Y155850D03*
X386777Y159005D03*
X380500Y162025D03*
X383700Y162199D03*
X383500Y159000D03*
X374300Y155800D03*
X377500Y165240D03*
Y156000D03*
X384740Y180080D03*
X381720Y180220D03*
X381800Y183300D03*
X380540Y177370D03*
X380500Y168500D03*
X383693Y171424D03*
X383548Y168390D03*
X386600Y174900D03*
X380477Y171605D03*
X376830Y175640D03*
X376800Y178600D03*
X384650Y183170D03*
X376742Y181524D03*
X381460Y195610D03*
X384390Y196470D03*
X381140Y187960D03*
X381280Y191550D03*
X384708Y188910D03*
X384600Y186100D03*
X376800Y193500D03*
X376900Y196600D03*
X380510Y185500D03*
X384684Y191950D03*
X373922Y193103D03*
X374000Y190350D03*
X379750Y213500D03*
X376300Y211000D03*
Y213700D03*
X384810Y208530D03*
X384644Y205994D03*
X382471Y199843D03*
X382600Y222600D03*
X382750Y229000D03*
X379700Y219200D03*
X385947Y226500D03*
X385900Y218400D03*
X376300Y216200D03*
X385900Y222600D03*
X382700Y226000D03*
X379700Y216500D03*
X372950Y217400D03*
X390700Y89300D03*
X403726Y83826D03*
X403700Y90200D03*
X397300Y89168D03*
X400400Y92200D03*
Y98500D03*
X390750Y96500D03*
X394100Y91400D03*
Y99000D03*
X397100Y96600D03*
X397300Y93100D03*
X392382Y102149D03*
X390650Y93000D03*
X394100Y94900D03*
X400400Y95000D03*
X393331Y118043D03*
X393351Y115107D03*
X397650Y115500D03*
X401749Y112418D03*
X401159Y119636D03*
X401353Y116562D03*
X396276Y120948D03*
X396251Y117999D03*
X396600Y112463D03*
X390683Y108042D03*
X400700Y108800D03*
X393653Y121122D03*
X389700Y112363D03*
X398500Y125604D03*
X398512Y122815D03*
X401500Y125600D03*
X393482Y123982D03*
X396700Y128000D03*
X389914Y124536D03*
X393561Y127130D03*
X401500Y122600D03*
X401256Y128755D03*
X397800Y130000D03*
X399452Y133964D03*
X389380Y130100D03*
X390100Y127600D03*
X390205Y133858D03*
X392998Y133968D03*
X396148D03*
X396321Y136987D03*
X402561Y137000D03*
X399298Y137118D03*
X392998D03*
X389848D03*
X402400Y140163D03*
X393000Y152663D03*
X402900Y149663D03*
X389721Y143320D03*
X393000Y140268D03*
X403132Y144374D03*
X396148Y140268D03*
X399298D03*
X389848Y146568D03*
X393204Y146436D03*
X403080Y146931D03*
X399198Y146468D03*
X396192Y146444D03*
X392998Y149718D03*
X399198Y149618D03*
X396182Y149674D03*
X396200Y152763D03*
X396300Y162100D03*
X399300Y152863D03*
Y155963D03*
X392998Y165240D03*
X396148Y155790D03*
X393208D03*
X399298Y165240D03*
X393028Y162059D03*
X393198Y158940D03*
X403078Y152922D03*
X402373Y155952D03*
X399298Y162090D03*
X402505Y159133D03*
X396148Y158940D03*
X399298D03*
X392599Y181686D03*
X400252Y182966D03*
X403600Y182400D03*
Y180200D03*
X402540Y171760D03*
X399300Y168400D03*
X402600Y174611D03*
X395573Y175400D03*
X396000Y179000D03*
X393077Y168455D03*
X399385Y171686D03*
X396225D03*
X390025Y174672D03*
X393085Y171686D03*
Y174836D03*
X400352Y180171D03*
X397100Y181000D03*
X400301Y186099D03*
X397805Y192061D03*
X392600Y190600D03*
X396200Y194700D03*
X392624Y184537D03*
X389500Y193600D03*
X397307Y186607D03*
X395600Y184100D03*
Y190300D03*
X392700Y193563D03*
X403022Y192094D03*
X402967Y195005D03*
X389484Y190442D03*
X389300Y187700D03*
X402962Y189014D03*
X392596Y187541D03*
X397728Y189053D03*
X395641Y188045D03*
X392100Y213700D03*
X395700Y213600D03*
X400400Y209400D03*
X398500Y208000D03*
X389100Y224000D03*
X399700Y225000D03*
Y216400D03*
X395600Y224400D03*
X395700Y217000D03*
X391950Y220800D03*
X389200Y227400D03*
X392000Y217200D03*
X395700Y220600D03*
X399800D03*
X389150Y230300D03*
X407500Y84000D03*
X407400Y91000D03*
X411300Y85600D03*
X414722Y90250D03*
X414300Y85600D03*
X403800Y87000D03*
X407400Y87400D03*
X411000Y88900D03*
X418300Y91300D03*
X418400Y98150D03*
X411000Y92100D03*
X414622Y98000D03*
X414672Y94500D03*
X417800Y100400D03*
X412650Y100197D03*
X418300Y94800D03*
X407550Y100196D03*
X404529Y118507D03*
X405900Y121700D03*
X409110Y114910D03*
X405200Y115343D03*
X412462Y115713D03*
X409196Y118195D03*
X416904Y119591D03*
X416922Y116613D03*
X413100Y121800D03*
X409110Y120910D03*
X404900Y124600D03*
X416000Y135983D03*
X415000Y131400D03*
X408956Y130064D03*
X418500Y128200D03*
X415100Y127900D03*
X406200Y127400D03*
X412100Y135600D03*
X416851Y122600D03*
X412600Y124100D03*
X412462Y126300D03*
X417753Y131322D03*
X404400Y128900D03*
X405500Y131063D03*
X414900Y147000D03*
X417900Y146900D03*
X408800Y147000D03*
X411900Y146800D03*
X413300Y139100D03*
X413400Y142700D03*
X418000Y142500D03*
X406000Y150200D03*
X407500Y152100D03*
X410400Y152000D03*
X415700Y143100D03*
X410302Y141864D03*
X405990Y144251D03*
X409096Y143963D03*
X406042Y147025D03*
X415100Y149800D03*
X407399Y142561D03*
X408837Y149809D03*
X418439Y167118D03*
X414800Y162600D03*
X411800Y162700D03*
X414572Y165913D03*
X411356Y165732D03*
X407500Y157600D03*
X412900Y157800D03*
X407400Y154863D03*
X406100Y159500D03*
X417785Y162622D03*
X413314Y154908D03*
X410100Y157700D03*
X415100Y158100D03*
X410272Y154794D03*
X416400Y155000D03*
X408600Y159600D03*
X411600D03*
X409300Y167163D03*
X408900Y162463D03*
X406000Y162663D03*
X404558Y154835D03*
X407100Y167429D03*
X418600Y182800D03*
X414960Y178130D03*
X414950Y181460D03*
X411260Y178090D03*
X411553Y181222D03*
X416400Y170300D03*
X413265Y170423D03*
X410408Y170261D03*
X410620Y173300D03*
X405100Y178500D03*
X408158Y178666D03*
X407552Y170424D03*
X416315Y183219D03*
X417900Y178363D03*
X415992Y189254D03*
Y186205D03*
X419097Y189563D03*
X416500Y195563D03*
X408242Y184624D03*
X405231Y184976D03*
X408200Y190500D03*
X408100Y193600D03*
X412500Y197300D03*
X405000Y190700D03*
X412000Y187500D03*
X412500Y194900D03*
X412100Y190400D03*
X418800Y196700D03*
X416139Y192007D03*
X411342Y185024D03*
X405800Y196700D03*
X405102Y187874D03*
X412200Y192600D03*
X416900Y200100D03*
X416353Y207249D03*
X408200Y226900D03*
X408100Y220500D03*
X404400Y228600D03*
Y222300D03*
X415600Y222700D03*
X415800Y215900D03*
X412050Y225100D03*
X412100Y218400D03*
X408200Y223800D03*
X412000Y222000D03*
X415700Y219200D03*
X404400Y225300D03*
X422078Y97678D03*
X422000Y91300D03*
X427560Y104770D03*
X429105Y106337D03*
X426800Y97850D03*
X429500Y93800D03*
X434021Y100128D03*
X422050Y94800D03*
X428100Y120000D03*
X424900Y121213D03*
X420600Y118300D03*
X420672Y120600D03*
X422042Y115224D03*
X424700Y115000D03*
X427900Y114300D03*
X428100Y116500D03*
X427500Y112091D03*
X430302Y112098D03*
X419596Y113463D03*
X425200Y118823D03*
X431188Y116105D03*
X430342Y119724D03*
X428255Y126236D03*
X425000Y135350D03*
X419500Y136400D03*
X430100Y131500D03*
X431700Y128300D03*
X423500Y128200D03*
X427000Y128050D03*
X423900Y131500D03*
X420942Y131324D03*
X422300Y126300D03*
X431504Y126061D03*
X424982Y126500D03*
X434700Y131800D03*
X432542Y136898D03*
X426982Y131334D03*
X427600Y143841D03*
X421500Y142400D03*
X426900Y147100D03*
X431100Y145500D03*
X424856Y142270D03*
X422400Y139000D03*
X420861Y149687D03*
Y146923D03*
X430694Y142275D03*
X428390Y139059D03*
X419499Y139064D03*
X423496Y144000D03*
X428363Y141756D03*
X423945Y165221D03*
X421710Y167230D03*
X431130Y166660D03*
X428238Y167709D03*
X420804Y162659D03*
X420900Y160037D03*
X425500Y154737D03*
X428400D03*
X426000Y167370D03*
X426900Y160040D03*
X430542Y160753D03*
X430600Y164513D03*
X431620Y154620D03*
X422363Y154700D03*
X434500Y160037D03*
X430360Y181350D03*
X430340Y177620D03*
X423642Y181374D03*
X426970Y178310D03*
X425400Y170240D03*
X428500Y173120D03*
X422337Y170575D03*
X425427Y173113D03*
X419453Y173187D03*
X420922Y178117D03*
X423842Y178274D03*
X428431Y170264D03*
X419340Y170500D03*
X421697Y174049D03*
X423910Y175700D03*
X432712Y172469D03*
X434482Y177021D03*
X432100Y190400D03*
X429100Y189696D03*
X426173Y190784D03*
X428830Y195379D03*
X422152Y189600D03*
X420800Y193100D03*
X421171Y196496D03*
X431270Y193425D03*
X425500Y186045D03*
X423966Y190846D03*
X423800Y196500D03*
X433842Y197021D03*
X421848Y186550D03*
X428400Y185900D03*
X429933Y197283D03*
X420975Y211300D03*
X427900Y202800D03*
X424832Y200174D03*
X421811Y202603D03*
X426311Y204399D03*
X421253Y199822D03*
X425642Y209524D03*
X419550Y222700D03*
X419600Y216200D03*
Y219200D03*
X444578Y106201D03*
X442378Y106198D03*
X440178Y106200D03*
X437400Y121600D03*
X442842Y120824D03*
X438700Y112900D03*
X438500Y116400D03*
X439400Y120100D03*
X434960Y114529D03*
X444242Y124324D03*
X435442Y124024D03*
X437800Y128100D03*
X439275Y124197D03*
X434700Y128200D03*
X443443Y144757D03*
X437398Y146257D03*
X435004Y142110D03*
X443400Y148900D03*
X437472Y152501D03*
X434834Y163817D03*
X439600Y153800D03*
X439276Y159645D03*
X435453Y167560D03*
X435105Y181207D03*
X438742Y197224D03*
X435642Y194824D03*
X437921Y192956D03*
X445000Y194500D03*
X443100Y195900D03*
X443000Y192700D03*
X435453Y185397D03*
X436957Y209867D03*
X459800Y118800D03*
X453000Y118700D03*
X456200Y118900D03*
X459700Y129900D03*
X452200Y129800D03*
X463100Y133700D03*
X456000Y133500D03*
X460100Y123100D03*
X453000Y123300D03*
X463200Y126200D03*
X456500Y126100D03*
X456200Y129600D03*
X459700Y133600D03*
X459800Y126200D03*
X456500Y123000D03*
X461200Y167400D03*
X454200D03*
X457700D03*
X464300Y181800D03*
X458000Y171100D03*
X451000D03*
X460000Y174900D03*
X453000D03*
X456500D03*
X454500Y171100D03*
X457400Y197000D03*
X450400D03*
X462500Y189000D03*
X460400Y193300D03*
X453400D03*
X456900D03*
X453900Y197000D03*
X459500Y200700D03*
X452500D03*
X456000D03*
X473900Y178200D03*
X466900D03*
X471300Y181800D03*
X470400Y178200D03*
X467800Y181800D03*
X473100Y185500D03*
X466000D03*
X469500Y189000D03*
X469600Y185500D03*
X466000Y189000D03*
X504000Y12507D03*
X506800Y12907D03*
X508700Y14607D03*
Y17207D03*
X511589Y30295D03*
X507839Y30362D03*
X506500Y32807D03*
X507817Y252248D03*
X511200Y258900D03*
X509244Y272796D03*
X506496Y272500D03*
X523453Y12360D03*
X511800Y12507D03*
X514360Y12417D03*
X526000Y12507D03*
X519426Y12318D03*
X520700Y14807D03*
X518769Y22907D03*
X515484D03*
X522311Y16720D03*
X514300Y20507D03*
X519623Y20457D03*
X525753Y30893D03*
X522733Y32832D03*
X522700Y30007D03*
X513005Y32412D03*
X519400Y33340D03*
X526700Y33207D03*
X511640Y255956D03*
X514137Y256089D03*
X522908Y255117D03*
X526715Y254700D03*
X516600Y252200D03*
X521800Y252875D03*
X513776Y258563D03*
X511736Y273001D03*
X514900Y271350D03*
X522992Y270700D03*
X525845Y272863D03*
X517846Y262489D03*
X521131D03*
X516727Y273122D03*
X521790Y273140D03*
X517100Y265100D03*
X521987D03*
X528525Y12549D03*
X537964Y12317D03*
X532500Y13407D03*
X541114Y12307D03*
X542100Y15107D03*
X530700Y15407D03*
X536485Y22907D03*
X533200D03*
X528219Y15096D03*
X532472Y20515D03*
X537410Y20584D03*
X542407Y30882D03*
X532350Y30807D03*
X529120Y32575D03*
X529000Y30007D03*
X541950Y33340D03*
X532542Y33307D03*
X537200Y33207D03*
X530015Y255000D03*
X531775Y252231D03*
X541005Y254800D03*
X532900Y255300D03*
X535098Y252600D03*
X540900Y252300D03*
X527400Y252100D03*
X530900Y273000D03*
X534100Y270700D03*
X541500Y270900D03*
X535562Y262489D03*
X538847D03*
X529300Y271000D03*
X528330Y273140D03*
X539937Y272989D03*
X539505Y265100D03*
X534905Y273097D03*
X534700Y265100D03*
X550000Y12507D03*
X544860Y12407D03*
X547500Y12507D03*
X553720Y12297D03*
X552800Y14807D03*
X557745Y22907D03*
X554460D03*
X550234Y14997D03*
X553797Y20496D03*
X549500Y29107D03*
X553079Y30712D03*
X549500Y31607D03*
X545928Y31047D03*
X553250Y33207D03*
X547306Y33134D03*
X544800Y255100D03*
X550200Y255500D03*
X551000Y252056D03*
X552800Y255300D03*
X545500Y252600D03*
X553485Y252332D03*
X544292Y273128D03*
X548800Y271000D03*
X551937Y272789D03*
X555641Y262489D03*
X546200Y271000D03*
X554500Y264900D03*
X546900Y273100D03*
X554434Y272914D03*
X568555Y12407D03*
X561200Y12507D03*
X558448Y12407D03*
X566040Y12317D03*
X571600Y14207D03*
X564400Y14307D03*
X566000Y16507D03*
X572200Y28707D03*
X558500Y20507D03*
X573200Y19907D03*
X570852Y33204D03*
X569800Y29807D03*
X565091Y30815D03*
X561456Y30902D03*
X565470Y33287D03*
X573242Y32462D03*
X560635Y33264D03*
X561419Y254850D03*
X565054Y254773D03*
X568327Y253348D03*
X571867Y254685D03*
X560555Y252503D03*
X563376Y256627D03*
X566151Y252115D03*
X572150Y252200D03*
X560600Y270300D03*
X564100Y271100D03*
X567800Y270500D03*
X570200Y273100D03*
X558926Y262489D03*
X570200Y269700D03*
X559600Y272900D03*
X572155Y264900D03*
X565700Y273050D03*
X559700Y264900D03*
X572700Y273100D03*
X587940Y12417D03*
X582655Y12407D03*
X573470Y12347D03*
X578620Y12357D03*
X585280Y12267D03*
X579800Y14807D03*
X577824Y22907D03*
X574539D03*
X583700Y28207D03*
X578600Y20307D03*
X585179Y30867D03*
X581450Y30707D03*
X579100Y33207D03*
X585550Y33340D03*
X587700Y255300D03*
X579205Y254850D03*
X582200Y252206D03*
X587642D03*
X582300Y254900D03*
X578800Y252200D03*
X580200Y273000D03*
X582600Y270300D03*
X588036Y273089D03*
X588400Y270300D03*
X573357Y262489D03*
X576642D03*
X577450Y264900D03*
X580107Y270501D03*
X577636Y272947D03*
X594600Y6707D03*
X590000Y14007D03*
X594500Y4007D03*
X600896Y12407D03*
X601704Y22907D03*
X601000Y20507D03*
X594400Y36207D03*
X589300Y33007D03*
X590500Y30507D03*
X594200Y33607D03*
X600360Y33287D03*
X594600Y260000D03*
X591300Y255010D03*
X590837Y259889D03*
X598398Y260199D03*
X591342Y252206D03*
X603187Y252056D03*
X589500Y257100D03*
X594500Y265200D03*
X591500Y270100D03*
X591536Y273000D03*
X590700Y264833D03*
X598300Y265400D03*
X589900Y268133D03*
X602450Y272900D03*
X598418Y262699D03*
X590322Y262361D03*
X594559Y262559D03*
X595386Y272932D03*
X610952Y12307D03*
X616600D03*
X605700Y12407D03*
X614700Y14107D03*
X615852Y19807D03*
X615907Y24856D03*
X607300Y14507D03*
X616707Y15616D03*
X604989Y22907D03*
X610800Y14807D03*
X605728Y20518D03*
X615951Y22356D03*
X612000Y17407D03*
X610944Y33333D03*
X607800Y30407D03*
X618900Y33290D03*
X615103Y30690D03*
X610500Y30507D03*
X615044Y33190D03*
X607544Y33340D03*
X618877Y30790D03*
X619382Y260089D03*
X615532Y259700D03*
X611706Y259387D03*
X606700Y255600D03*
X604074Y254394D03*
X609500Y254900D03*
X609937Y252106D03*
X608700Y257300D03*
X611845Y253723D03*
X615537Y264789D03*
X619100Y265300D03*
X611536Y264385D03*
X609896Y272889D03*
X608996Y270206D03*
X605100Y270100D03*
X605065Y272967D03*
X611593Y261885D03*
X606200Y267800D03*
X615430Y262213D03*
X612393Y273026D03*
X619180Y262689D03*
X633500Y12406D03*
X624000D03*
X623532Y20007D03*
X623555Y25107D03*
X619607Y19807D03*
X627255Y25107D03*
X627231Y19907D03*
X630955Y25207D03*
X631000Y20107D03*
X634555Y25307D03*
X634757Y20207D03*
X619730Y24864D03*
X634757Y22707D03*
X623480Y22564D03*
X631007Y22707D03*
X619700Y22307D03*
X627257Y22407D03*
X624100Y33190D03*
X633449D03*
X630432Y260100D03*
X626682Y260300D03*
X622933Y260189D03*
X634207Y260300D03*
X630455Y265400D03*
X634280Y265332D03*
X626651Y265489D03*
X622899Y265189D03*
X629937Y272990D03*
X630457Y262832D03*
X626680Y262989D03*
X634280Y262832D03*
X620437Y272990D03*
X622930Y262689D03*
X644193Y12907D03*
X648800Y12707D03*
X641745Y12367D03*
X638400Y20607D03*
X638290Y25674D03*
X642246Y25807D03*
X642451Y20707D03*
X645300Y15507D03*
X648400Y15490D03*
X645200Y27707D03*
X646800Y17607D03*
X642257Y23307D03*
X638507Y23183D03*
X647000Y29607D03*
X649550Y30807D03*
X643700Y33290D03*
X644100Y30307D03*
X650200Y33307D03*
X641900Y31507D03*
X638032Y260342D03*
X642802Y252186D03*
X645920Y254130D03*
X635043Y252106D03*
X638900Y254809D03*
X643020Y254710D03*
X647800Y252300D03*
X635197Y254602D03*
X638893Y252206D03*
X638090Y265340D03*
X642937Y273089D03*
X646360Y271530D03*
X637288Y270100D03*
X637337Y272944D03*
X648948Y262489D03*
X644090Y270420D03*
X648200Y265300D03*
X637987Y262842D03*
X644550Y267170D03*
X639500Y268800D03*
X648291Y273140D03*
X662359Y12379D03*
X657897Y12504D03*
X651316Y12360D03*
X659400Y25907D03*
Y20474D03*
X662192Y14874D03*
X663202Y25973D03*
X655602Y25223D03*
X663200Y20956D03*
X655700Y20225D03*
X664212Y16356D03*
X663300Y23454D03*
X662916Y28457D03*
X655592Y22723D03*
X659400Y23207D03*
X662503Y33207D03*
X657900Y30690D03*
X664678Y30307D03*
X661708Y30699D03*
X657900Y33190D03*
X659437Y246389D03*
X665500Y252189D03*
X665300Y254700D03*
X661200Y248500D03*
X653600Y252130D03*
X659500Y274000D03*
X665100Y272700D03*
X652233Y262489D03*
X664500Y270000D03*
X653000Y264900D03*
X661600Y272300D03*
X653041Y272989D03*
X671290Y12457D03*
X665901Y12307D03*
X675990Y12357D03*
X674320Y14219D03*
X666175Y14807D03*
X680580Y22807D03*
X677295D03*
X669600Y17907D03*
X676600Y20307D03*
X671500Y15007D03*
X674400Y31307D03*
X671295Y33190D03*
X671900Y30707D03*
X675970Y33267D03*
X670200Y254700D03*
X673770Y254752D03*
X669930Y252150D03*
X674636Y252406D03*
X669700Y270900D03*
X672800Y272700D03*
X676113Y262489D03*
X679398D03*
X680600Y265000D03*
X675400D03*
X668000Y272890D03*
X680400Y273100D03*
X675400D03*
X690102Y12502D03*
X684760Y12256D03*
X687602Y12439D03*
X694200Y13507D03*
X681280Y12457D03*
X692200Y15357D03*
X682013Y14848D03*
X695029Y22853D03*
X684500Y15507D03*
X689595Y27883D03*
X685400Y28307D03*
X681700Y20507D03*
X694205Y20302D03*
X693300Y30607D03*
X689624Y30383D03*
X685700Y30807D03*
X681900Y30907D03*
X693700Y33107D03*
X681280Y33340D03*
X687900Y33327D03*
X682800Y254900D03*
X685382Y252200D03*
X688800Y254600D03*
X692250Y255700D03*
X690000Y256800D03*
X685390Y254900D03*
X688720Y252090D03*
X693860Y252210D03*
X681900Y252500D03*
X682481Y270700D03*
X685100Y273100D03*
X689700Y270800D03*
X692537Y272989D03*
X696192Y262489D03*
X691900Y269300D03*
X683100Y268000D03*
X695500Y265000D03*
Y273100D03*
X687682Y272889D03*
X709000Y12407D03*
X702000Y12607D03*
X699503Y12482D03*
X706360Y12397D03*
X705031Y14515D03*
X698277Y22855D03*
X705604Y16949D03*
X710813Y28796D03*
X699104Y20495D03*
X708900Y30407D03*
X704430Y33313D03*
X701800Y30807D03*
X707157Y33333D03*
X700940Y33340D03*
X701649Y255049D03*
X704178Y252189D03*
X707800Y255000D03*
X711400Y255072D03*
X704137Y254796D03*
X699800Y252230D03*
X701704Y257549D03*
X707490Y252310D03*
X701300Y270777D03*
X704277Y272989D03*
X709400Y272600D03*
X699477Y262489D03*
X706000Y270500D03*
X700200Y264900D03*
X700300Y273100D03*
X706900Y273000D03*
X723586Y14080D03*
X712182Y14124D03*
X714000Y12407D03*
X719110Y12347D03*
X725530Y12507D03*
X720100Y14707D03*
X718375Y22907D03*
X715090D03*
X714100Y20607D03*
X719220Y20553D03*
X727000Y30407D03*
X723500Y29907D03*
X721747Y32954D03*
X712400Y30807D03*
X721074Y30514D03*
X718350Y33107D03*
X712450Y33340D03*
X725653Y32654D03*
X721500Y255000D03*
X724374Y254515D03*
X712350Y252640D03*
X725950Y252573D03*
X721395Y252175D03*
X721600Y257500D03*
X716737Y252189D03*
X712200Y270500D03*
X722400Y270800D03*
X725300Y272800D03*
X717452Y262489D03*
X720737D03*
X716795Y265000D03*
X721400D03*
X721395Y273100D03*
X713100Y273000D03*
X716737Y272989D03*
X715900Y270000D03*
X742200Y12407D03*
X728010Y12857D03*
X737300Y12307D03*
X732110Y12267D03*
X739000Y14407D03*
X731169Y14584D03*
X736091Y23607D03*
X732806D03*
X728500Y15507D03*
X742100Y28107D03*
X732000Y20307D03*
X736748D03*
X728500Y27907D03*
X742100Y33007D03*
X740200Y29907D03*
X730500D03*
X733474Y33340D03*
X738487Y33094D03*
X730400Y255400D03*
X732200Y252200D03*
X741560Y255000D03*
X730300Y257900D03*
X734937Y253100D03*
X739750Y252800D03*
X730400Y272850D03*
X732740Y270200D03*
X741200Y270500D03*
X735168Y262489D03*
X738453D03*
X729860Y269810D03*
X734200Y265100D03*
X739111Y264962D03*
X739838Y272813D03*
X727800Y272800D03*
X734510Y273110D03*
X745100Y12256D03*
X744900Y20500D03*
X745000Y23000D03*
X744800Y33007D03*
X747441D03*
X744437Y252189D03*
X744100Y254800D03*
X749000Y252200D03*
X744200Y272600D03*
X753000Y272100D03*
X746737Y272889D03*
X948450Y450250D03*
G54D13*
X17500Y190200D03*
X17301Y212401D03*
X16844Y203100D03*
X17300Y218307D03*
X10000Y229500D03*
X16400Y224212D03*
X16118Y230118D03*
X10194Y243106D03*
X9500Y234200D03*
X13090Y231129D03*
Y234899D03*
X7600Y240861D03*
Y237091D03*
X16899Y241929D03*
X16300Y236023D03*
X13590Y242940D03*
X10190Y258510D03*
X10194Y254917D03*
X10190Y246699D03*
X16899Y247834D03*
Y253740D03*
X13590Y254751D03*
X7600Y252672D03*
X16899Y259645D03*
X7600Y248902D03*
Y260713D03*
X13590Y258521D03*
Y246710D03*
X16900Y269000D03*
X7600Y264483D03*
Y268100D03*
X16899Y265551D03*
X28400Y81400D03*
X32800Y120400D03*
X25800Y120300D03*
X29200D03*
X30000Y136000D03*
X29700Y141200D03*
X26500Y181800D03*
X33500Y178100D03*
X33150Y181500D03*
X29400Y180000D03*
X23100Y181800D03*
X30000Y196200D03*
X33500Y196100D03*
X21900Y205400D03*
X31500Y207500D03*
X32000Y203200D03*
Y199300D03*
X41200Y90300D03*
X42000Y96000D03*
X41500Y100800D03*
X40500Y127700D03*
Y124300D03*
X38500Y148000D03*
X48500D03*
X41000Y152300D03*
Y143300D03*
X46000D03*
Y152300D03*
X43500Y148000D03*
Y138500D03*
X48500D03*
X38500D03*
X45800Y158100D03*
X37600Y198800D03*
X34800D03*
X37900Y195300D03*
X40400Y212700D03*
X34800Y208300D03*
X40400Y207800D03*
X34800Y203700D03*
X37600Y212700D03*
X34800Y212200D03*
X37600Y207800D03*
Y203700D03*
X34500Y216000D03*
X40400Y217100D03*
X40700Y224000D03*
X44861Y227261D03*
X37900Y219000D03*
Y222500D03*
Y229500D03*
Y226000D03*
X40200Y238300D03*
Y231300D03*
X37900Y240000D03*
Y243500D03*
X40200Y245300D03*
X37900Y233000D03*
X38000Y236500D03*
X44400Y250400D03*
X40500Y260000D03*
X37900Y257500D03*
Y254000D03*
X40600Y252500D03*
X37900Y247000D03*
X38000Y250500D03*
X46800Y274500D03*
X62900Y79900D03*
X60800Y87500D03*
X52500Y96500D03*
Y106500D03*
X57500Y96500D03*
X60000Y101500D03*
X50000D03*
X55000D03*
X57500Y106500D03*
X53500Y120400D03*
X60000Y111300D03*
X50000D03*
X55000D03*
X57600Y136900D03*
X56100Y130700D03*
X52643Y130800D03*
X58000Y141750D03*
X58800Y177000D03*
X54700Y192200D03*
X52700Y184800D03*
X62800Y184300D03*
X51860Y187640D03*
Y191410D03*
X59379Y184380D03*
X55720D03*
X57600Y214200D03*
X57400Y210700D03*
X57009Y230009D03*
X57600Y226600D03*
X57500Y223200D03*
X57287Y219806D03*
X56724Y243300D03*
X56800Y249613D03*
X58102Y246471D03*
X57800Y253900D03*
X50000Y270000D03*
X57800Y264100D03*
X64700Y272500D03*
X57800Y267500D03*
X80031Y40357D03*
X76411D03*
X74000Y37642D03*
X66500D03*
X79700Y67500D03*
X79115Y60979D03*
X78300Y64300D03*
X69235Y99735D03*
X68200Y94900D03*
Y91500D03*
X66500Y128000D03*
X65500Y123800D03*
X74800Y191000D03*
X72137Y210237D03*
X79500Y230000D03*
X72600Y244800D03*
X78700Y259800D03*
X75600Y246700D03*
X79000Y246900D03*
X69400Y246000D03*
X67600Y255800D03*
X75300Y259900D03*
X66300Y259300D03*
X78200Y275600D03*
X71800Y268800D03*
X66800Y275200D03*
X74000Y271400D03*
X67000Y263200D03*
X82211Y37747D03*
X92159Y40357D03*
X89862Y37849D03*
X89400Y58200D03*
X83600Y57600D03*
X88700Y54400D03*
X85300D03*
X90600Y63200D03*
X94000Y63300D03*
X82885Y60979D03*
X90000Y91000D03*
X91500Y84000D03*
X94500Y76200D03*
X89800Y87300D03*
X86100Y97700D03*
X90500Y101000D03*
X86500Y113500D03*
X80500D03*
X85500Y135400D03*
X83500Y191000D03*
X86900D03*
X84700Y197100D03*
X92900Y204008D03*
X89500Y204000D03*
X85898Y200598D03*
X95200Y216200D03*
X90812Y215000D03*
X80563Y214700D03*
X84500Y230000D03*
X89500D03*
X84500Y225000D03*
Y235000D03*
X88900Y246700D03*
X82400Y246600D03*
X82100Y259600D03*
X80500Y269500D03*
X91400Y270300D03*
X83900Y269500D03*
X95779Y40357D03*
X98500Y37642D03*
X107907Y40357D03*
X105794Y37692D03*
X109700Y60000D03*
X104400Y57700D03*
X96800Y53300D03*
X103450Y54400D03*
X100050D03*
X109600Y63700D03*
X96200Y60700D03*
X97900Y76200D03*
X106100Y158700D03*
X95700Y197200D03*
X97100Y189200D03*
X110000Y201900D03*
X107740Y204460D03*
X102000Y203200D03*
X99600Y225700D03*
X100600Y221100D03*
X110166Y239500D03*
X99328Y235370D03*
X109000Y231400D03*
X109500Y258300D03*
X97600Y246500D03*
X104900Y248800D03*
X120000Y40700D03*
X113605Y37665D03*
X121500Y37642D03*
X123655Y40357D03*
X111527D03*
X121400Y60100D03*
X120200Y45610D03*
X119200Y57400D03*
X115800D03*
X111200Y67200D03*
X114800Y60700D03*
X121170Y80900D03*
X121295Y77502D03*
X126000Y86200D03*
X125787Y78813D03*
X120700Y135500D03*
X118500Y125500D03*
X112550Y142800D03*
X119600Y143300D03*
X120500Y139000D03*
X125000Y178000D03*
X119760Y191419D03*
X115760D03*
X123760D03*
X111900Y209000D03*
X112800Y225400D03*
X112700Y221200D03*
Y231400D03*
X136600Y44800D03*
X139403Y40357D03*
X129336Y37652D03*
X127275Y40357D03*
X137300Y37642D03*
X138000Y49800D03*
X138574Y57924D03*
X131600Y57400D03*
X135000D03*
X136400Y60600D03*
X130400D03*
X136469Y89902D03*
X130315Y90533D03*
X134200Y86100D03*
X137138Y76512D03*
X129300Y84900D03*
X136600Y93300D03*
X133558Y91779D03*
X136500Y104923D03*
Y101523D03*
X130000Y121000D03*
X136770Y113000D03*
X136540Y108620D03*
X133975Y129141D03*
X130563Y125200D03*
X127500Y129180D03*
X126950Y125200D03*
X133786Y134700D03*
X130300Y135000D03*
X136500Y126300D03*
X135412Y141400D03*
X138600Y146300D03*
X131500Y149000D03*
X136156Y138025D03*
X131762Y141796D03*
X127200Y158700D03*
X137300Y158900D03*
X132700Y158600D03*
X140800Y158900D03*
X140000Y195500D03*
X137100Y188900D03*
X128000Y203300D03*
X143023Y40357D03*
X153088Y37653D03*
X145070Y37642D03*
X155151Y40357D03*
X144995Y57995D03*
X143700Y54503D03*
X154615Y54500D03*
X155290Y48610D03*
X143688Y48350D03*
X147400Y60400D03*
X147315Y54400D03*
X150715D03*
X153000Y67800D03*
X152811Y84300D03*
X150894Y76497D03*
X154294Y76506D03*
X150670Y102720D03*
X154550Y106200D03*
X151080Y99344D03*
X154550Y102800D03*
X157175Y115462D03*
X150670Y115500D03*
Y118900D03*
Y112100D03*
X157229Y119218D03*
X150670Y122300D03*
X153693Y124807D03*
X147808Y145208D03*
X142900Y138595D03*
X146400D03*
X150804Y158896D03*
X144500Y158900D03*
X150500Y183000D03*
X157000Y169194D03*
X146980Y200580D03*
X153000Y201900D03*
X153500Y210000D03*
X146396Y207675D03*
X142997Y207891D03*
X150000Y210100D03*
X146500Y236500D03*
X146000Y231000D03*
X155300Y254000D03*
X144200Y270700D03*
X168791Y37689D03*
X158771Y40357D03*
X170899D03*
X160898Y37704D03*
X169600Y53000D03*
X159957Y51932D03*
X159060Y48610D03*
X170290Y49600D03*
X166463Y54400D03*
X163063D03*
X167500Y68000D03*
X164000Y65000D03*
X158105Y96775D03*
X172199Y91591D03*
X172300Y107189D03*
X158305Y112180D03*
X171800Y126600D03*
X157500Y149025D03*
X162900Y152200D03*
X158500Y161820D03*
X161900Y161700D03*
X167602Y160684D03*
X167581Y164084D03*
X170910Y173840D03*
X167140D03*
X165900Y181500D03*
X163700Y178900D03*
X169800Y181448D03*
X165700Y203400D03*
X162000Y226000D03*
X167000D03*
Y221500D03*
X162000D03*
Y230500D03*
X167000D03*
X162000Y235000D03*
X165700Y254000D03*
X174519Y40357D03*
X176640Y37699D03*
X184500Y37700D03*
X186647Y40357D03*
X185000Y51600D03*
X175758Y52879D03*
X174060Y49600D03*
X186865Y54300D03*
X181800Y54400D03*
X179000D03*
X179800Y65700D03*
X176900Y67500D03*
X180700Y78500D03*
X184300D03*
X174900Y77700D03*
X183726Y106353D03*
X187500Y106500D03*
X173000Y97000D03*
X183344Y94056D03*
X179400Y94200D03*
X181732Y97500D03*
X178000Y97300D03*
X175787Y127000D03*
X177200Y130575D03*
X187597Y133697D03*
X176700Y144875D03*
X177200Y148700D03*
X181000Y167500D03*
X180931Y172985D03*
X177159Y172900D03*
X176400Y175700D03*
X186300Y172400D03*
X185546Y192509D03*
X180546D03*
X175546D03*
X174739Y207381D03*
X177500Y209500D03*
X187000D03*
X176800Y241600D03*
X198073Y40395D03*
X194445D03*
X192400Y37642D03*
X200300D03*
X190267Y40357D03*
X191700Y52100D03*
X201500Y54500D03*
X189700Y54300D03*
X197700Y54400D03*
X194700D03*
X190100Y68700D03*
X196900D03*
X193500D03*
X194075Y80360D03*
X197845D03*
X202200Y89500D03*
X198500Y83800D03*
X193485Y83724D03*
X191500Y94100D03*
X188900Y91800D03*
X202500Y97000D03*
X193005Y97155D03*
X195989Y95300D03*
X189106Y97235D03*
X188363Y116137D03*
X201650Y111200D03*
X201899Y134200D03*
X194900Y124200D03*
X197140Y152010D03*
X194623Y149723D03*
X201252Y137766D03*
X192237Y147300D03*
X199900Y154200D03*
X191200Y181068D03*
X200900Y177000D03*
X199441Y187547D03*
X199392Y190947D03*
X202761Y186811D03*
X195630Y192770D03*
X202800Y191400D03*
X196000Y186897D03*
X198198Y206374D03*
X194800Y206100D03*
X201596Y206504D03*
X191400Y206100D03*
X195000Y234000D03*
X207600Y37642D03*
X216085Y37649D03*
X210900Y57600D03*
X205300Y54900D03*
X208700D03*
X214942Y67242D03*
X211600Y82100D03*
X212300Y85500D03*
X207200Y106000D03*
X213558Y98500D03*
X205689Y112879D03*
X205850Y118175D03*
X209259Y113771D03*
Y117430D03*
X206605Y121741D03*
X209900Y120900D03*
X205380Y134200D03*
X210100Y135800D03*
X210547Y139028D03*
X206790Y139040D03*
X213850Y179850D03*
X215100Y194200D03*
X207861Y188540D03*
X215100Y199400D03*
X205000Y206500D03*
X215384Y202984D03*
X205920Y221550D03*
X216000Y219500D03*
X208800D03*
X212500D03*
X206000Y234000D03*
X229300Y42950D03*
X232591Y43057D03*
X219900Y39100D03*
X223868Y37686D03*
X231780Y37691D03*
X223475Y53300D03*
X219899Y56800D03*
X233981Y59125D03*
X221400Y64500D03*
X230400Y63000D03*
X223800Y61700D03*
X230000Y66400D03*
X229036Y83000D03*
X226500Y94450D03*
X227850Y97575D03*
X230875Y106300D03*
X227894Y104600D03*
X232600Y95300D03*
X227800Y101200D03*
X233452Y108588D03*
X228000Y108304D03*
X231562Y143827D03*
X231611Y138336D03*
X226452Y147300D03*
X228000Y139700D03*
X232921Y167505D03*
X233350Y180700D03*
X227870Y170252D03*
X224200Y180200D03*
X232225Y193275D03*
X232560Y204250D03*
X227000Y275500D03*
X236211Y43057D03*
X239599Y37673D03*
X245385Y40357D03*
X241765D03*
X247500Y37642D03*
X244400Y50600D03*
X238800Y45300D03*
X240200Y59275D03*
X247500Y60000D03*
X235400Y63400D03*
X240297D03*
X243200Y73700D03*
X240300Y67200D03*
X246600Y73700D03*
X244759Y85200D03*
X236700Y88500D03*
X241200Y94900D03*
X244800Y100700D03*
X235075Y105600D03*
X244463Y130655D03*
X234875Y139290D03*
Y143060D03*
X244715Y159785D03*
X242950Y155800D03*
X239900Y180600D03*
X247596Y174667D03*
X236477Y179357D03*
X240119Y183993D03*
X240100Y191000D03*
X236861Y184967D03*
X246689Y196687D03*
X254600Y41100D03*
X261900Y44900D03*
X265140Y40490D03*
X255000Y37642D03*
X263100Y37700D03*
X264700Y59400D03*
X256200Y59200D03*
X259000Y57800D03*
X250500Y57900D03*
X262000Y57800D03*
X253500Y57900D03*
X264500Y73100D03*
X253700Y75875D03*
X250300Y73800D03*
X264125Y79350D03*
X264189Y98252D03*
X259820Y103454D03*
X262131Y100959D03*
X258634Y95850D03*
X263775Y140327D03*
X257977Y163423D03*
X264600Y173100D03*
X257687Y169870D03*
X253500Y174360D03*
X261300Y188300D03*
X253300Y189834D03*
X262700Y191500D03*
X261200Y209700D03*
X263600Y239850D03*
Y252700D03*
X257500Y266645D03*
X260500Y264630D03*
X269800Y44800D03*
X275300Y44900D03*
X278700Y44800D03*
X271000Y37800D03*
X278800Y37700D03*
X268910Y40490D03*
X278868Y56000D03*
X274000Y55800D03*
X271000Y57500D03*
X268000D03*
X275200Y78700D03*
X275900Y88200D03*
X280100Y89100D03*
X268928Y112625D03*
X272200Y108352D03*
X268895Y107350D03*
X272185Y111831D03*
X278075Y116475D03*
X272300Y129442D03*
X268900Y129386D03*
X280400Y129225D03*
X272300Y149900D03*
X267187Y149800D03*
X268300Y141869D03*
X278000Y141900D03*
X273900Y156198D03*
X270500Y163200D03*
X274100Y163300D03*
X267456Y160156D03*
X267100Y156200D03*
X272380Y159240D03*
X270500Y156250D03*
X268283Y173035D03*
X278300Y173300D03*
X269772Y188274D03*
X276910Y189400D03*
X273060Y189374D03*
X266140Y191850D03*
X270341Y211835D03*
X278450Y216800D03*
X265259Y216659D03*
X270774Y222226D03*
X274700Y222100D03*
X275400Y237900D03*
X267275Y253400D03*
X265500Y249300D03*
X269800Y250700D03*
X278700Y254240D03*
X275300Y254100D03*
X267000Y271300D03*
X284758Y40490D03*
X280988D03*
X286900Y37800D03*
X294500Y37900D03*
X292500Y60500D03*
X284000Y55800D03*
X286800Y57900D03*
X290200D03*
X288700Y71100D03*
X292100D03*
X295300Y66200D03*
X288400Y94200D03*
X288100Y99500D03*
X281005Y99105D03*
X281475Y116475D03*
X286500Y119900D03*
X286600Y136000D03*
X285100Y129510D03*
X281500Y142100D03*
X295900Y154200D03*
X287071Y173154D03*
X282950Y181350D03*
X282460Y189400D03*
X286300Y191885D03*
X287700Y211900D03*
X293300Y212400D03*
X291201Y225025D03*
X287802Y225200D03*
X295300Y238100D03*
X287600D03*
X287400Y254100D03*
X295500Y253500D03*
X285000Y261700D03*
X281599Y261799D03*
X287250Y269250D03*
X310348Y37900D03*
X296736Y40490D03*
X300506D03*
X302600Y37800D03*
X302400Y59500D03*
X300900Y46900D03*
X308200Y57400D03*
X304800D03*
X297150Y91100D03*
X309400Y82100D03*
X299800Y85950D03*
Y82300D03*
X304400Y88400D03*
X306100Y90600D03*
X301300Y97000D03*
X301600Y93300D03*
X303400Y98500D03*
X303376Y95200D03*
X299300Y98500D03*
X296564Y136311D03*
Y127500D03*
X296531Y133061D03*
X301109Y146156D03*
X300700Y142850D03*
X297000Y160200D03*
X307231Y164059D03*
X297250Y163700D03*
X310579Y182800D03*
X306612Y171882D03*
X304400Y182000D03*
X302591Y173906D03*
X309112Y171960D03*
X309200Y180500D03*
X305091Y173888D03*
X301745Y181788D03*
X307200Y182000D03*
X296600Y189100D03*
X305300Y203125D03*
X307300Y224900D03*
X304400D03*
X309900D03*
X298900Y253300D03*
X309400Y253600D03*
X306000D03*
X302600D03*
X304300Y262900D03*
X309000Y266700D03*
X311300Y277800D03*
X321900Y44000D03*
X326096Y37900D03*
X318048Y37700D03*
X312484Y40690D03*
X316254D03*
X314800Y48625D03*
X311950Y50800D03*
X320400Y48600D03*
X311598Y57522D03*
X322548Y58300D03*
X324000Y54900D03*
X324176Y48600D03*
X315800Y57400D03*
X319200D03*
X323882Y71643D03*
X318882D03*
X312400Y79700D03*
X312150Y100682D03*
X326000Y254100D03*
X315500D03*
X322500Y254200D03*
X319000D03*
X311400Y269200D03*
X326100Y267000D03*
X322000Y264300D03*
X318600D03*
X313824Y280255D03*
X316945Y281606D03*
X316400Y276800D03*
X319400Y278800D03*
X322700Y277700D03*
X321600Y282500D03*
X325100Y281500D03*
X331931Y40995D03*
X328303D03*
X333700Y38000D03*
X331300Y48475D03*
X327577D03*
X328300Y58200D03*
X327400Y54900D03*
X333600Y63800D03*
X337000Y74202D03*
X328882Y71643D03*
X356432Y43657D03*
X356971Y37700D03*
X349900Y263800D03*
X342600Y277900D03*
X364600Y44298D03*
X363583Y37642D03*
X367497Y41042D03*
X363604D03*
X371457Y37642D03*
X367520D03*
X366484Y47129D03*
X362626Y47068D03*
X366700Y68700D03*
X369500Y237200D03*
Y240600D03*
X373000Y242300D03*
X369500Y234600D03*
X373000Y236000D03*
Y238900D03*
X369500Y244000D03*
X365800Y264900D03*
X362400D03*
X369300D03*
X375400Y37700D03*
X385300Y47000D03*
X388000Y72963D03*
X382700Y275300D03*
X380000Y263461D03*
X383500D03*
X376500D03*
X386100Y275300D03*
X379300D03*
X394229Y241128D03*
X391788Y238760D03*
X393000Y236200D03*
X397400Y239700D03*
X399438Y243839D03*
X401838Y246248D03*
X390500Y268800D03*
X393000Y275000D03*
X400900Y273000D03*
X391000Y265000D03*
X389500Y275300D03*
X405700Y246500D03*
X417000Y258000D03*
X416128Y272896D03*
X425400Y9103D03*
X422000D03*
X428800D03*
X432200D03*
X430500Y17000D03*
X430000Y21500D03*
Y27358D03*
X424543Y22208D03*
Y27900D03*
X426405Y25054D03*
X427000Y17000D03*
X423500Y16885D03*
X423000Y43900D03*
X430000Y30758D03*
X424536Y34800D03*
X430000Y34158D03*
X424599Y31300D03*
X422986Y40350D03*
X430000Y244450D03*
X426600D03*
X420000Y244000D03*
X420500Y257800D03*
X433129Y245783D03*
X423600Y246700D03*
X423900Y257500D03*
X423000Y274000D03*
X433300Y274100D03*
X426600D03*
X429900Y274940D03*
X442100Y7006D03*
X437061Y10393D03*
X434900Y6925D03*
X446800Y9900D03*
X438300Y6925D03*
X449600Y5900D03*
X446200D03*
X446100Y18700D03*
X441390Y28680D03*
X444783Y28451D03*
X436240Y26300D03*
X449734Y18681D03*
X441281Y17025D03*
X436100Y30900D03*
X436106Y34506D03*
X435700Y243250D03*
X445300Y274400D03*
X440600Y274300D03*
X449400Y273700D03*
X436600Y275000D03*
X450200Y9800D03*
X451300Y21700D03*
X451000Y257413D03*
X464000Y275200D03*
X456300Y275300D03*
X460400Y275200D03*
X452500D03*
X480400Y154050D03*
X467100Y154200D03*
X477000Y154050D03*
X470100Y154200D03*
X473500Y154050D03*
X467700Y245500D03*
X469000Y275200D03*
X472400Y275100D03*
X466500Y272800D03*
X472101Y266090D03*
X475500Y265900D03*
X479000D03*
X493000Y119299D03*
X483800Y154050D03*
X487200Y154100D03*
X495400Y183500D03*
X482400Y266200D03*
X502000Y89000D03*
X498500Y88995D03*
X508000Y119500D03*
X511500D03*
X511200Y183400D03*
X500900D03*
X504400D03*
X510675Y209700D03*
X505315Y268500D03*
X497002Y275400D03*
X525740Y88960D03*
X522280Y89810D03*
X515502Y88998D03*
X518902Y88987D03*
X524700Y119500D03*
X515000Y119270D03*
X524700Y145041D03*
X518200Y183400D03*
X526600Y183500D03*
X514800Y183400D03*
X513100Y234500D03*
X516500D03*
X528985Y89975D03*
X533267Y89634D03*
X539574Y88990D03*
X533000Y119500D03*
X536400D03*
X528100D03*
X528400Y145041D03*
X541550Y183550D03*
X534750Y183600D03*
X538150D03*
X530214Y183481D03*
X531500Y219500D03*
X531000Y228350D03*
X541500Y234900D03*
X551800Y69600D03*
X548400Y69700D03*
X555199D03*
X556500Y89000D03*
X546349Y89512D03*
X552900Y89100D03*
X542950Y89400D03*
X552100Y136000D03*
X557100D03*
X555500Y183500D03*
X548354Y183600D03*
X544954D03*
X551754D03*
X548300Y209700D03*
X551700Y209800D03*
X550400Y222285D03*
X561999Y69700D03*
X558599D03*
X570715Y89100D03*
X566000D03*
X572100Y136000D03*
X567100D03*
X562000Y127800D03*
X562100Y136000D03*
X562000Y144900D03*
X572845Y183300D03*
X566897Y183405D03*
X561900Y183600D03*
X564398Y183481D03*
X569395Y183300D03*
X558915Y183603D03*
X558300Y210000D03*
X561000Y222700D03*
X561196Y227366D03*
X569200Y223600D03*
X564200Y224000D03*
X575000Y89100D03*
X587500Y88913D03*
X578400Y89100D03*
X588600Y124700D03*
X584800Y183300D03*
X582254Y183313D03*
X576295Y183400D03*
X588475Y183300D03*
X578795D03*
X573600Y190100D03*
X586800Y213200D03*
X583800Y207200D03*
X580350Y207250D03*
X599500Y87500D03*
X590898Y89045D03*
X596845Y89624D03*
X599300Y119270D03*
X593400Y126000D03*
X588800Y145000D03*
X592200D03*
X599200D03*
X595744Y145041D03*
X599150Y180300D03*
X593475Y183275D03*
X601750Y182500D03*
X590975Y183275D03*
X594350Y187725D03*
X591850D03*
X588800Y205900D03*
X591363Y208387D03*
X602800Y203225D03*
X601200Y207700D03*
X603964Y210400D03*
X612120Y121750D03*
X608360Y121800D03*
X617700Y125500D03*
X608300Y144890D03*
X618500Y159000D03*
X605600Y186650D03*
X609345Y190100D03*
X607500Y188300D03*
X616100Y197400D03*
X634000Y97500D03*
X630700Y100500D03*
X627500Y104900D03*
X620000Y112575D03*
X624726Y107395D03*
X621100Y124900D03*
X625500Y159000D03*
X629000D03*
X622000D03*
X633319Y155008D03*
X631900Y175850D03*
X634748Y177708D03*
X633100Y198300D03*
X626300Y198250D03*
X629700Y198300D03*
X622873Y204200D03*
X642823Y88477D03*
X640677Y91115D03*
X638500Y94000D03*
X635000Y110500D03*
X638000Y107400D03*
X639500Y136490D03*
X648500Y144000D03*
X636719Y154972D03*
X643500Y155000D03*
X648500Y162600D03*
X640110Y155272D03*
X640461Y181410D03*
X642600Y186400D03*
X646000D03*
X636500Y198300D03*
X653600Y122400D03*
X656477Y148033D03*
X656642Y151430D03*
X656200Y144000D03*
X661600Y156700D03*
X650500Y155000D03*
X661000Y173800D03*
X657722Y193800D03*
X661600Y197300D03*
X654851Y191978D03*
X663800Y199900D03*
X654100Y221800D03*
X673100Y179455D03*
X676200Y181600D03*
X673044Y190456D03*
X668732Y204555D03*
X666446Y202037D03*
X682600Y114300D03*
X684700Y179800D03*
X689400Y178900D03*
X689547Y175500D03*
X686700Y187400D03*
X687456Y183944D03*
X694600Y229800D03*
X705145Y93500D03*
X707209Y97500D03*
X698970Y118149D03*
X699241Y114759D03*
X709500Y143500D03*
X709900Y139900D03*
X698000Y181500D03*
X701245Y183800D03*
X704700D03*
X718900Y94000D03*
X726800Y95500D03*
X724200Y108400D03*
X714000Y118500D03*
X727448Y128893D03*
X715700Y124200D03*
X714900Y131900D03*
X727187Y140000D03*
X718200Y147000D03*
Y150400D03*
X718825Y155453D03*
X712700Y155978D03*
X724400Y176025D03*
X717000Y187500D03*
X725500Y195500D03*
X715500Y205837D03*
X727400Y227400D03*
X738000Y65700D03*
X738500Y90000D03*
X731340Y82515D03*
X736900Y98500D03*
X730200Y94900D03*
X739500Y114900D03*
X742100Y118200D03*
X736300Y118000D03*
X729400Y120200D03*
X732000Y122700D03*
X728900Y132976D03*
X727800Y136600D03*
X741104Y133763D03*
X740300Y164700D03*
X736900Y162300D03*
X729500D03*
X733400D03*
X727800Y176600D03*
X733000Y176200D03*
X737000Y188315D03*
X739900Y212800D03*
X734000Y205000D03*
X731000Y210200D03*
X739800Y216300D03*
X750100Y16100D03*
X752500Y49007D03*
X756000Y106000D03*
X749500Y101500D03*
X751300Y118200D03*
X754000Y115100D03*
X748800Y115800D03*
X758176Y135024D03*
X757900Y124700D03*
X745104Y129763D03*
X749104Y133763D03*
X745104D03*
X752191Y146613D03*
X745104Y137763D03*
X747000Y162000D03*
X750500D03*
X746000Y182300D03*
X743100Y195500D03*
X743000Y211000D03*
X744100Y221900D03*
X743800Y215900D03*
X758916Y104250D03*
X762304Y103957D03*
X768500Y114000D03*
X765500Y112000D03*
X769800Y133000D03*
X759400Y131000D03*
X771300Y140200D03*
X766600Y139800D03*
X762000Y281000D03*
X765400D03*
X774500Y31307D03*
X778000D03*
X779000Y142000D03*
X788515Y144060D03*
X784515D03*
X787600Y183300D03*
X787800Y179900D03*
X796515Y144060D03*
X792515D03*
X800515D03*
Y148060D03*
X796515D03*
X792515D03*
X793000Y174500D03*
X805500Y128000D03*
X948450Y422150D03*
G54D23*
X350197Y231103D03*
X948450Y56850D03*
G54D14*
X45669Y77185D03*
Y172460D03*
X948450Y113050D03*
G54D24*
X804032Y27032D03*
X794032D03*
X804032Y37032D03*
Y47032D03*
X794032Y37032D03*
Y47032D03*
X804032Y57032D03*
X794032D03*
X804032Y67032D03*
X794032D03*
X948450Y309750D03*
G54D15*
X42717Y191732D03*
X948450Y197350D03*
G54D25*
G01X10636Y-27865D02*
G02I-12000J0D01*
G01X14636D02*
X-17364D01*
G01X5486D02*
G02I-6850J0D01*
G01X-1364Y-43865D02*
Y-11865D01*
G01X14636Y-43865D02*
Y-123865D01*
G01D02*
X1309236D01*
G01X14636Y-79365D02*
X1309236D01*
G01X14636Y-43865D02*
X1309236D01*
G01X521736D02*
Y-123865D01*
G01X659236Y-43865D02*
Y-123865D01*
G01X774236Y-43865D02*
Y-123865D01*
G01X941736Y-43865D02*
Y-123865D01*
G01X1111736Y-43865D02*
Y-123865D01*
G01X1309236Y-43865D02*
Y-123865D01*
G01X1341236Y-27865D02*
X1309236D01*
G01X1337236D02*
G02I-12000J0D01*
G01X1332086D02*
G02I-6850J0D01*
G01X1325236Y-43865D02*
Y-11865D01*
G54D16*
X42717Y270472D03*
X235630Y75590D03*
X492520Y262598D03*
D03*
X761417Y22798D03*
D03*
X948450Y253550D03*
G54D26*
G01X-31497Y-1D02*
X26377D01*
G01X-35434Y3936D02*
G03X-31497Y-1I3937J0D01*
G01X-35434Y585039D02*
Y3936D01*
G01X-7874Y588976D02*
X-31497D01*
G01D02*
G03X-35434Y585039I0J-3937D01*
G01X-12698Y15747D02*
G03I-6988J0D01*
G01Y573227D02*
G03I-6988J0D01*
G01X826773Y286614D02*
G03X822836Y290551I-3937J0D01*
G01X3938D01*
G03X1Y286614I0J-3937D01*
G01Y61811D01*
G03X3938Y57874I3937J0D01*
G01X53938D01*
G02X57875Y53937I0J-3937D01*
G01Y12598D01*
X59844Y10629D01*
X336222D01*
X338190Y12598D01*
Y39960D01*
G02X345671I3740J0D01*
G01Y12598D01*
X347639Y10629D01*
X387797D01*
X389765Y12598D01*
Y42126D01*
G02X393702Y46063I3937J0D01*
G01X409450D01*
G02X413387Y42126I0J-3937D01*
G01Y3937D01*
G03X417324Y0I3937J0D01*
G01X822836D01*
G03X826773Y3937I0J3937D01*
G01Y286614D01*
G01X22440Y49999D02*
X-3937D01*
G01X-7874Y53936D02*
Y72440D01*
G01Y53936D02*
G03X-3937Y49999I3937J0D01*
G01X0Y72440D02*
G03X-7874I-3937J0D01*
G01Y103149D02*
G03X0I3937J0D01*
G01X-7874D02*
Y210235D01*
G01X0D02*
G03X-7874I-3937J0D01*
G01Y240944D02*
Y348031D01*
G01Y240944D02*
G03X0I3937J0D01*
G01X-3Y302361D02*
G03X3934Y298424I3937J0D01*
G01X822832D01*
G03X826769Y302361I0J3937D01*
G01Y527164D01*
G03X822832Y531101I-3937J0D01*
G01X772832D01*
G02X768895Y535038I0J3937D01*
G01Y576377D01*
X766926Y578346D01*
X490548D01*
X488580Y576377D01*
Y549015D01*
G02X481099I-3740J0D01*
G01Y576377D01*
X479131Y578346D01*
X438973D01*
X437005Y576377D01*
Y546849D01*
G02X433068Y542912I-3937J0D01*
G01X417320D01*
G02X413383Y546849I0J3937D01*
G01Y585038D01*
G03X409446Y588975I-3937J0D01*
G01X3934D01*
G03X-3Y585038I0J-3937D01*
G01Y302361D01*
G01X0Y348031D02*
G03X-7874I-3937J0D01*
G01Y378739D02*
Y485826D01*
G01Y378739D02*
G03X0I3937J0D01*
G01Y485826D02*
G03X-7874I-3937J0D01*
G01Y516535D02*
Y588976D01*
G01Y516535D02*
G03X0I3937J-1D01*
G01X26377Y-1D02*
Y46062D01*
G01D02*
G03X22440Y49999I-3937J0D01*
G01X70851Y-113865D02*
Y-96365D01*
G01X80021D02*
Y-113865D01*
G01Y-105115D02*
X70851D01*
G01X92936Y-113865D02*
X91626Y-113573D01*
X90316Y-112407D01*
X89442Y-110365D01*
X89006Y-108032D01*
X89442Y-105698D01*
X90316Y-103657D01*
X91626Y-102490D01*
X92936Y-102199D01*
X94246Y-102490D01*
X95556Y-103657D01*
X96429Y-105698D01*
X96648Y-108032D01*
X96429Y-110365D01*
X95556Y-112407D01*
X94246Y-113573D01*
X92936Y-113865D01*
G01X106724D02*
Y-102199D01*
G01Y-105115D02*
X107598Y-103657D01*
X108908Y-102490D01*
X110654Y-102199D01*
X112182Y-102490D01*
X113493Y-103657D01*
X114148Y-105698D01*
Y-113865D01*
G01X124661Y-105990D02*
X131648D01*
X130993Y-103948D01*
X129901Y-102782D01*
X128373Y-102199D01*
X126844Y-102490D01*
X125534Y-103365D01*
X124661Y-105407D01*
X124224Y-107157D01*
Y-108907D01*
X124661Y-110657D01*
X125753Y-112407D01*
X127063Y-113573D01*
X128591Y-113865D01*
X130119Y-113282D01*
X131648Y-111532D01*
G01X140851Y-119115D02*
X142161Y-119698D01*
X143908Y-119115D01*
X144999Y-117949D01*
X145873Y-116490D01*
X147182Y-111824D01*
X150021Y-102199D01*
G01X143034D02*
X147182Y-111824D01*
G01X182182Y-104532D02*
X183056Y-103657D01*
X183711Y-102199D01*
X184148Y-100156D01*
X183711Y-98407D01*
X182838Y-97240D01*
X181309Y-96365D01*
X175414D01*
Y-113865D01*
X182619D01*
X184148Y-112699D01*
X185021Y-110948D01*
X185458Y-108907D01*
X185021Y-106865D01*
X183711Y-105115D01*
X182182Y-104532D01*
X175414D01*
G01X201866Y-113865D02*
Y-102199D01*
G01Y-104240D02*
X200993Y-103074D01*
X199682Y-102490D01*
X198154Y-102199D01*
X196626Y-102782D01*
X195316Y-103948D01*
X194442Y-105698D01*
X194006Y-108032D01*
X194442Y-110365D01*
X195316Y-112115D01*
X196626Y-113282D01*
X198154Y-113865D01*
X199682Y-113573D01*
X200993Y-112699D01*
X201866Y-111532D01*
G01X219366Y-96365D02*
Y-113865D01*
G01Y-111241D02*
X218493Y-112699D01*
X217182Y-113573D01*
X215654Y-113865D01*
X213908Y-113282D01*
X212598Y-111824D01*
X211724Y-110074D01*
X211506Y-108032D01*
X211724Y-105990D01*
X212598Y-104240D01*
X213908Y-102782D01*
X215654Y-102199D01*
X217182Y-102490D01*
X218274Y-103074D01*
X219366Y-104240D01*
G01X229879Y-118240D02*
X231408Y-119407D01*
X233154Y-119698D01*
X234682Y-119407D01*
X235993Y-117949D01*
X236866Y-115907D01*
Y-102199D01*
G01Y-104532D02*
X235993Y-103365D01*
X234682Y-102490D01*
X233154Y-102199D01*
X231408Y-102782D01*
X230316Y-103948D01*
X229442Y-105990D01*
X229006Y-108032D01*
X229224Y-109782D01*
X230098Y-111824D01*
X231408Y-113282D01*
X233154Y-113865D01*
X234464Y-113573D01*
X235993Y-112407D01*
X236866Y-111241D01*
G01X247161Y-105990D02*
X254148D01*
X253493Y-103948D01*
X252401Y-102782D01*
X250873Y-102199D01*
X249344Y-102490D01*
X248034Y-103365D01*
X247161Y-105407D01*
X246724Y-107157D01*
Y-108907D01*
X247161Y-110657D01*
X248253Y-112407D01*
X249563Y-113573D01*
X251091Y-113865D01*
X252619Y-113282D01*
X254148Y-111532D01*
G01X264879Y-113865D02*
Y-102199D01*
G01Y-104532D02*
X265971Y-103365D01*
X267063Y-102490D01*
X268591Y-102199D01*
X269682Y-102490D01*
X270993Y-103365D01*
G01X298569Y-113865D02*
Y-96365D01*
X303809D01*
X305556Y-97240D01*
X306866Y-99282D01*
X307303Y-101615D01*
X306866Y-103948D01*
X305774Y-105698D01*
X303809Y-106574D01*
X298569D01*
G01X324366Y-113865D02*
Y-102199D01*
G01Y-104240D02*
X323493Y-103074D01*
X322182Y-102490D01*
X320654Y-102199D01*
X319126Y-102782D01*
X317816Y-103948D01*
X316942Y-105698D01*
X316506Y-108032D01*
X316942Y-110365D01*
X317816Y-112115D01*
X319126Y-113282D01*
X320654Y-113865D01*
X322182Y-113573D01*
X323493Y-112699D01*
X324366Y-111532D01*
G01X334224Y-113865D02*
Y-102199D01*
G01Y-105115D02*
X335098Y-103657D01*
X336408Y-102490D01*
X338154Y-102199D01*
X339682Y-102490D01*
X340993Y-103657D01*
X341648Y-105698D01*
Y-113865D01*
G01X355436Y-96365D02*
Y-113865D01*
G01X352379Y-102199D02*
X358493D01*
G01X369224Y-113865D02*
Y-96365D01*
G01Y-104823D02*
X370316Y-103365D01*
X371408Y-102490D01*
X373154Y-102199D01*
X374464Y-102490D01*
X375993Y-103657D01*
X376648Y-105407D01*
Y-113865D01*
G01X387161Y-105990D02*
X394148D01*
X393493Y-103948D01*
X392401Y-102782D01*
X390873Y-102199D01*
X389344Y-102490D01*
X388034Y-103365D01*
X387161Y-105407D01*
X386724Y-107157D01*
Y-108907D01*
X387161Y-110657D01*
X388253Y-112407D01*
X389563Y-113573D01*
X391091Y-113865D01*
X392619Y-113282D01*
X394148Y-111532D01*
G01X404879Y-113865D02*
Y-102199D01*
G01Y-104532D02*
X405971Y-103365D01*
X407063Y-102490D01*
X408591Y-102199D01*
X409682Y-102490D01*
X410993Y-103365D01*
G01X437259Y-113865D02*
Y-96365D01*
X442936Y-110948D01*
X448613Y-96365D01*
Y-113865D01*
G01X462182Y-104532D02*
X463056Y-103657D01*
X463711Y-102199D01*
X464148Y-100156D01*
X463711Y-98407D01*
X462838Y-97240D01*
X461309Y-96365D01*
X455414D01*
Y-113865D01*
X462619D01*
X464148Y-112699D01*
X465021Y-110948D01*
X465458Y-108907D01*
X465021Y-106865D01*
X463711Y-105115D01*
X462182Y-104532D01*
X455414D01*
G01X102756Y290550D02*
G03Y298424I0J3937D01*
G01X133465D02*
G03Y290550I0J-3937D01*
G01X227259Y-68865D02*
Y-51365D01*
X232936Y-65948D01*
X238613Y-51365D01*
Y-68865D01*
G01X250436D02*
X249126Y-68573D01*
X247816Y-67407D01*
X246942Y-65365D01*
X246506Y-63032D01*
X246942Y-60698D01*
X247816Y-58657D01*
X249126Y-57490D01*
X250436Y-57199D01*
X251746Y-57490D01*
X253056Y-58657D01*
X253929Y-60698D01*
X254148Y-63032D01*
X253929Y-65365D01*
X253056Y-67407D01*
X251746Y-68573D01*
X250436Y-68865D01*
G01X271866Y-51365D02*
Y-68865D01*
G01Y-66241D02*
X270993Y-67699D01*
X269682Y-68573D01*
X268154Y-68865D01*
X266408Y-68282D01*
X265098Y-66824D01*
X264224Y-65074D01*
X264006Y-63032D01*
X264224Y-60990D01*
X265098Y-59240D01*
X266408Y-57782D01*
X268154Y-57199D01*
X269682Y-57490D01*
X270774Y-58074D01*
X271866Y-59240D01*
G01X282161Y-60990D02*
X289148D01*
X288493Y-58948D01*
X287401Y-57782D01*
X285873Y-57199D01*
X284344Y-57490D01*
X283034Y-58365D01*
X282161Y-60407D01*
X281724Y-62157D01*
Y-63907D01*
X282161Y-65657D01*
X283253Y-67407D01*
X284563Y-68573D01*
X286091Y-68865D01*
X287619Y-68282D01*
X289148Y-66532D01*
G01X302936Y-68865D02*
Y-51365D01*
G01X299606Y290551D02*
G03Y298425I0J3937D01*
G01X330314D02*
G03Y290551I0J-3937D01*
G01X350147Y224753D02*
X350097Y219053D01*
G01X351603Y219740D02*
X350147Y224753D01*
X348603Y219766D01*
X351603Y219740D01*
G01X347047Y224803D02*
X353347D01*
G03Y237403I0J6300D01*
G01X347047D01*
G03Y224803I0J-6300D01*
G01X496457Y290550D02*
G03Y298424I0J3937D01*
G01X527166D02*
G03Y290550I0J-3937D01*
G01X542319Y-68865D02*
Y-51365D01*
X547559D01*
X549306Y-52240D01*
X550616Y-54282D01*
X551053Y-56615D01*
X550616Y-58948D01*
X549524Y-60698D01*
X547559Y-61574D01*
X542319D01*
G01X568989Y-52824D02*
X567679Y-51948D01*
X566151Y-51365D01*
X564404D01*
X562439Y-52240D01*
X560911Y-53698D01*
X559819Y-55449D01*
X558946Y-58365D01*
X558727Y-60990D01*
X559164Y-63615D01*
X559819Y-65365D01*
X561129Y-67115D01*
X562658Y-68282D01*
X564186Y-68865D01*
X565714D01*
X567243Y-68282D01*
X568553Y-67407D01*
X569645Y-66241D01*
G01X583432Y-59532D02*
X584306Y-58657D01*
X584961Y-57199D01*
X585398Y-55156D01*
X584961Y-53407D01*
X584088Y-52240D01*
X582559Y-51365D01*
X576664D01*
Y-68865D01*
X583869D01*
X585398Y-67699D01*
X586271Y-65948D01*
X586708Y-63907D01*
X586271Y-61865D01*
X584961Y-60115D01*
X583432Y-59532D01*
X576664D01*
G01X592636Y-74698D02*
X605736D01*
G01X611664Y-68865D02*
Y-51365D01*
X621708Y-68865D01*
Y-51365D01*
G01X634186Y-68865D02*
X632439Y-68573D01*
X630911Y-67407D01*
X629601Y-65657D01*
X628727Y-63615D01*
X628291Y-61282D01*
Y-58948D01*
X628727Y-56615D01*
X629601Y-54573D01*
X630911Y-52824D01*
X632439Y-51657D01*
X634186Y-51365D01*
X635932Y-51657D01*
X637461Y-52824D01*
X638771Y-54573D01*
X639645Y-56615D01*
X640081Y-58948D01*
Y-61282D01*
X639645Y-63615D01*
X638771Y-65657D01*
X637461Y-67407D01*
X635932Y-68573D01*
X634186Y-68865D01*
G01X555436Y-113865D02*
Y-96365D01*
X552816Y-99865D01*
G01Y-113865D02*
X558056D01*
G01X568133Y-110365D02*
X569442Y-112407D01*
X571189Y-113573D01*
X573154Y-113865D01*
X574901Y-113573D01*
X576648Y-112115D01*
X577739Y-110365D01*
X577958Y-108615D01*
X577521Y-106574D01*
X575993Y-105115D01*
X574464Y-104532D01*
X572499D01*
G01X574464D02*
X575774Y-103657D01*
X576866Y-102199D01*
X577303Y-100449D01*
X576866Y-98698D01*
X575774Y-97240D01*
X573809Y-96365D01*
X571844Y-96657D01*
X569879Y-97824D01*
G01X590436Y-113865D02*
Y-96365D01*
X587816Y-99865D01*
G01Y-113865D02*
X593056D01*
G01X603133Y-110365D02*
X604442Y-112407D01*
X606189Y-113573D01*
X608154Y-113865D01*
X609901Y-113573D01*
X611648Y-112115D01*
X612739Y-110365D01*
X612958Y-108615D01*
X612521Y-106574D01*
X610993Y-105115D01*
X609464Y-104532D01*
X607499D01*
G01X609464D02*
X610774Y-103657D01*
X611866Y-102199D01*
X612303Y-100449D01*
X611866Y-98698D01*
X610774Y-97240D01*
X608809Y-96365D01*
X606844Y-96657D01*
X604879Y-97824D01*
G01X625436Y-96365D02*
X623689Y-96948D01*
X622379Y-98407D01*
X621506Y-100156D01*
X620851Y-102490D01*
X620633Y-105115D01*
X620851Y-107740D01*
X621506Y-110074D01*
X622379Y-111824D01*
X623689Y-113282D01*
X625436Y-113865D01*
X627182Y-113282D01*
X628493Y-111824D01*
X629366Y-110074D01*
X630021Y-107740D01*
X630239Y-105115D01*
X630021Y-102490D01*
X629366Y-100156D01*
X628493Y-98407D01*
X627182Y-96948D01*
X625436Y-96365D01*
G01X685027Y-51365D02*
X690486Y-68865D01*
X695945Y-51365D01*
G01X712353Y-68865D02*
X703619D01*
Y-51365D01*
X712353D01*
G01X708859Y-59823D02*
X703619D01*
G01X721119Y-68865D02*
Y-51365D01*
X726578D01*
X728324Y-52240D01*
X729416Y-53407D01*
X729853Y-55740D01*
X729416Y-58074D01*
X728106Y-59532D01*
X726578Y-60407D01*
X721119D01*
G01X726578D02*
X729853Y-68865D01*
G01X742986Y-69448D02*
X742549Y-69157D01*
Y-68573D01*
X742986Y-68282D01*
X743423Y-68573D01*
Y-69157D01*
X742986Y-69448D01*
G01X693308Y290550D02*
G03Y298424I0J3937D01*
G01X707986Y-113865D02*
Y-96365D01*
X705366Y-99865D01*
G01Y-113865D02*
X710606D01*
G01X727232Y-104532D02*
X728106Y-103657D01*
X728761Y-102199D01*
X729198Y-100156D01*
X728761Y-98407D01*
X727888Y-97240D01*
X726359Y-96365D01*
X720464D01*
Y-113865D01*
X727669D01*
X729198Y-112699D01*
X730071Y-110948D01*
X730508Y-108907D01*
X730071Y-106865D01*
X728761Y-105115D01*
X727232Y-104532D01*
X720464D01*
G01X724016Y298424D02*
G03Y290550I0J-3937D01*
G01X800393Y588976D02*
Y542913D01*
G01D02*
G03X804330Y538976I3937J0D01*
G01X858267Y588976D02*
X800393D01*
G01X818133Y-113865D02*
Y-96365D01*
X822499D01*
X824246Y-97240D01*
X825556Y-98407D01*
X826648Y-100156D01*
X827521Y-102199D01*
X827739Y-105115D01*
X827521Y-108032D01*
X826648Y-110074D01*
X825556Y-111824D01*
X824246Y-112990D01*
X822499Y-113865D01*
X818133D01*
G01X836069D02*
Y-96365D01*
X841528D01*
X843274Y-97240D01*
X844366Y-98407D01*
X844803Y-100740D01*
X844366Y-103074D01*
X843056Y-104532D01*
X841528Y-105407D01*
X836069D01*
G01X841528D02*
X844803Y-113865D01*
G01X855316Y-96365D02*
X860556D01*
G01X857936D02*
Y-113865D01*
G01X855316D02*
X860556D01*
G01X871069Y-96365D02*
Y-113865D01*
X879803D01*
G01X888569Y-96365D02*
Y-113865D01*
X897303D01*
G01X818569Y-51365D02*
Y-68865D01*
X827303D01*
G01X844366D02*
Y-57199D01*
G01Y-59240D02*
X843493Y-58074D01*
X842182Y-57490D01*
X840654Y-57199D01*
X839126Y-57782D01*
X837816Y-58948D01*
X836942Y-60698D01*
X836506Y-63032D01*
X836942Y-65365D01*
X837816Y-67115D01*
X839126Y-68282D01*
X840654Y-68865D01*
X842182Y-68573D01*
X843493Y-67699D01*
X844366Y-66532D01*
G01X853351Y-74115D02*
X854661Y-74698D01*
X856408Y-74115D01*
X857499Y-72949D01*
X858373Y-71490D01*
X859682Y-66824D01*
X862521Y-57199D01*
G01X855534D02*
X859682Y-66824D01*
G01X872161Y-60990D02*
X879148D01*
X878493Y-58948D01*
X877401Y-57782D01*
X875873Y-57199D01*
X874344Y-57490D01*
X873034Y-58365D01*
X872161Y-60407D01*
X871724Y-62157D01*
Y-63907D01*
X872161Y-65657D01*
X873253Y-67407D01*
X874563Y-68573D01*
X876091Y-68865D01*
X877619Y-68282D01*
X879148Y-66532D01*
G01X889879Y-68865D02*
Y-57199D01*
G01Y-59532D02*
X890971Y-58365D01*
X892063Y-57490D01*
X893591Y-57199D01*
X894682Y-57490D01*
X895993Y-58365D01*
G01X804330Y538976D02*
X830708D01*
G01X834645Y72440D02*
G03X826771I-3937J0D01*
G01Y103149D02*
G03X834645I3937J0D01*
G01Y210235D02*
G03X826771I-3937J0D01*
G01Y240944D02*
G03X834645I3937J0D01*
G01Y348031D02*
G03X826771I-3937J0D01*
G01Y378739D02*
G03X834645I3937J0D01*
G01Y485826D02*
G03X826771I-3937J0D01*
G01Y516535D02*
G03X834645I3937J-1D01*
G01Y535039D02*
G03X830708Y538976I-3937J0D01*
G01X834645Y72440D02*
Y-1D01*
G01D02*
X858267D01*
G01X853444Y15747D02*
G03I-6988J0D01*
G01X834645Y210235D02*
Y103149D01*
G01Y348031D02*
Y240944D01*
G01Y485826D02*
Y378739D01*
G01Y535039D02*
Y516535D01*
G01X853444Y573227D02*
G03I-6988J0D01*
G01X862204Y3936D02*
Y585039D01*
G01X858267Y-1D02*
G03X862204Y3936I0J3937D01*
G01Y585039D02*
G03X858267Y588976I-3937J0D01*
G01X904585Y12800D02*
Y25300D01*
X911715Y12800D01*
Y25300D01*
G01X920550Y12800D02*
X919620Y13008D01*
X918690Y13841D01*
X918070Y15300D01*
X917760Y16967D01*
X918070Y18633D01*
X918690Y20092D01*
X919620Y20925D01*
X920550Y21133D01*
X921480Y20925D01*
X922410Y20092D01*
X923030Y18633D01*
X923185Y16967D01*
X923030Y15300D01*
X922410Y13841D01*
X921480Y13008D01*
X920550Y12800D01*
G01X932950Y25300D02*
Y12800D01*
G01X930780Y21133D02*
X935120D01*
G01X943025Y18425D02*
X947985D01*
X947520Y19883D01*
X946745Y20717D01*
X945660Y21133D01*
X944575Y20925D01*
X943645Y20300D01*
X943025Y18842D01*
X942715Y17591D01*
Y16342D01*
X943025Y15092D01*
X943800Y13841D01*
X944730Y13008D01*
X945815Y12800D01*
X946900Y13217D01*
X947985Y14466D01*
G01X957750Y12383D02*
X957440Y12592D01*
Y13008D01*
X957750Y13217D01*
X958060Y13008D01*
Y12592D01*
X957750Y12383D01*
G01Y18008D02*
X957440Y18217D01*
Y18633D01*
X957750Y18842D01*
X958060Y18633D01*
Y18217D01*
X957750Y18008D01*
G01X967050Y12800D02*
Y25300D01*
X970925D01*
X972165Y24675D01*
X972940Y23842D01*
X973250Y22175D01*
X972940Y20508D01*
X972010Y19467D01*
X970925Y18842D01*
X967050D01*
G01X970925D02*
X973250Y12800D01*
G01X980225Y18425D02*
X985185D01*
X984720Y19883D01*
X983945Y20717D01*
X982860Y21133D01*
X981775Y20925D01*
X980845Y20300D01*
X980225Y18842D01*
X979915Y17591D01*
Y16342D01*
X980225Y15092D01*
X981000Y13841D01*
X981930Y13008D01*
X983015Y12800D01*
X984100Y13217D01*
X985185Y14466D01*
G01X994020Y12800D02*
Y23425D01*
X994330Y24466D01*
X994950Y25092D01*
X995880Y25300D01*
X996810Y24883D01*
X997275Y23842D01*
G01X995415Y20300D02*
X992315D01*
G01X1005025Y18425D02*
X1009985D01*
X1009520Y19883D01*
X1008745Y20717D01*
X1007660Y21133D01*
X1006575Y20925D01*
X1005645Y20300D01*
X1005025Y18842D01*
X1004715Y17591D01*
Y16342D01*
X1005025Y15092D01*
X1005800Y13841D01*
X1006730Y13008D01*
X1007815Y12800D01*
X1008900Y13217D01*
X1009985Y14466D01*
G01X1017580Y12800D02*
Y21133D01*
G01Y19467D02*
X1018355Y20300D01*
X1019130Y20925D01*
X1020215Y21133D01*
X1020990Y20925D01*
X1021920Y20300D01*
G01X1044550Y25300D02*
Y12800D01*
G01X1042380Y21133D02*
X1046720D01*
G01X1056950Y12800D02*
X1056020Y13008D01*
X1055090Y13841D01*
X1054470Y15300D01*
X1054160Y16967D01*
X1054470Y18633D01*
X1055090Y20092D01*
X1056020Y20925D01*
X1056950Y21133D01*
X1057880Y20925D01*
X1058810Y20092D01*
X1059430Y18633D01*
X1059585Y16967D01*
X1059430Y15300D01*
X1058810Y13841D01*
X1057880Y13008D01*
X1056950Y12800D01*
G01X1078340D02*
Y25300D01*
X1081440D01*
X1082680Y24675D01*
X1083610Y23842D01*
X1084385Y22592D01*
X1085005Y21133D01*
X1085160Y19050D01*
X1085005Y16967D01*
X1084385Y15508D01*
X1083610Y14258D01*
X1082680Y13425D01*
X1081440Y12800D01*
X1078340D01*
G01X1091050D02*
Y25300D01*
X1094925D01*
X1096165Y24675D01*
X1096940Y23842D01*
X1097250Y22175D01*
X1096940Y20508D01*
X1096010Y19467D01*
X1094925Y18842D01*
X1091050D01*
G01X1094925D02*
X1097250Y12800D01*
G01X1104690Y25300D02*
X1108410D01*
G01X1106550D02*
Y12800D01*
G01X1104690D02*
X1108410D01*
G01X1115850Y25300D02*
Y12800D01*
X1122050D01*
G01X1128250Y25300D02*
Y12800D01*
X1134450D01*
G01X1156150D02*
Y25300D01*
G01X1171340Y12800D02*
Y21133D01*
G01Y19675D02*
X1170720Y20508D01*
X1169790Y20925D01*
X1168705Y21133D01*
X1167620Y20717D01*
X1166690Y19883D01*
X1166070Y18633D01*
X1165760Y16967D01*
X1166070Y15300D01*
X1166690Y14050D01*
X1167620Y13217D01*
X1168705Y12800D01*
X1169790Y13008D01*
X1170720Y13633D01*
X1171340Y14466D01*
G01X1177695Y9050D02*
X1178625Y8633D01*
X1179865Y9050D01*
X1180640Y9883D01*
X1181260Y10925D01*
X1182190Y14258D01*
X1184205Y21133D01*
G01X1179245D02*
X1182190Y14258D01*
G01X1191025Y18425D02*
X1195985D01*
X1195520Y19883D01*
X1194745Y20717D01*
X1193660Y21133D01*
X1192575Y20925D01*
X1191645Y20300D01*
X1191025Y18842D01*
X1190715Y17591D01*
Y16342D01*
X1191025Y15092D01*
X1191800Y13841D01*
X1192730Y13008D01*
X1193815Y12800D01*
X1194900Y13217D01*
X1195985Y14466D01*
G01X1203580Y12800D02*
Y21133D01*
G01Y19467D02*
X1204355Y20300D01*
X1205130Y20925D01*
X1206215Y21133D01*
X1206990Y20925D01*
X1207920Y20300D01*
G01X1229620Y12800D02*
Y23425D01*
X1229930Y24466D01*
X1230550Y25092D01*
X1231480Y25300D01*
X1232410Y24883D01*
X1232875Y23842D01*
G01X1231015Y20300D02*
X1227915D01*
G01X1242950Y12800D02*
X1242020Y13008D01*
X1241090Y13841D01*
X1240470Y15300D01*
X1240160Y16967D01*
X1240470Y18633D01*
X1241090Y20092D01*
X1242020Y20925D01*
X1242950Y21133D01*
X1243880Y20925D01*
X1244810Y20092D01*
X1245430Y18633D01*
X1245585Y16967D01*
X1245430Y15300D01*
X1244810Y13841D01*
X1243880Y13008D01*
X1242950Y12800D01*
G01X1253180D02*
Y21133D01*
G01Y19467D02*
X1253955Y20300D01*
X1254730Y20925D01*
X1255815Y21133D01*
X1256590Y20925D01*
X1257520Y20300D01*
G01X1283250Y12800D02*
X1277050D01*
Y25300D01*
X1283250D01*
G01X1280770Y19258D02*
X1277050D01*
G01X1289450Y25300D02*
Y12800D01*
X1295650D01*
G01X1301850Y25300D02*
Y12800D01*
X1308050D01*
G01X1315490Y25300D02*
X1319210D01*
G01X1317350D02*
Y12800D01*
G01X1315490D02*
X1319210D01*
G01X1326650D02*
Y25300D01*
X1330370D01*
X1331610Y24675D01*
X1332540Y23217D01*
X1332850Y21550D01*
X1332540Y19883D01*
X1331765Y18633D01*
X1330370Y18008D01*
X1326650D01*
G01X1338895Y14466D02*
X1340135Y13425D01*
X1341530Y12800D01*
X1342770D01*
X1344010Y13425D01*
X1344940Y14466D01*
X1345405Y15925D01*
X1345095Y17383D01*
X1344320Y18633D01*
X1342925Y19467D01*
X1341065Y19883D01*
X1339980Y20717D01*
X1339515Y22175D01*
X1339825Y23633D01*
X1340600Y24675D01*
X1341685Y25300D01*
X1342770D01*
X1343855Y24883D01*
X1344785Y23842D01*
G01X1357650Y12800D02*
X1351450D01*
Y25300D01*
X1357650D01*
G01X1355170Y19258D02*
X1351450D01*
G01X1382140Y25300D02*
Y12800D01*
G01Y14675D02*
X1381520Y13633D01*
X1380590Y13008D01*
X1379505Y12800D01*
X1378265Y13217D01*
X1377335Y14258D01*
X1376715Y15508D01*
X1376560Y16967D01*
X1376715Y18425D01*
X1377335Y19675D01*
X1378265Y20717D01*
X1379505Y21133D01*
X1380590Y20925D01*
X1381365Y20508D01*
X1382140Y19675D01*
G01X1389580Y12800D02*
Y21133D01*
G01Y19467D02*
X1390355Y20300D01*
X1391130Y20925D01*
X1392215Y21133D01*
X1392990Y20925D01*
X1393920Y20300D01*
G01X1404150Y21133D02*
Y12800D01*
G01Y24466D02*
X1403840Y24675D01*
Y25092D01*
X1404150Y25300D01*
X1404460Y25092D01*
Y24675D01*
X1404150Y24466D01*
G01X1416550Y12800D02*
Y25300D01*
G01X1428950Y12800D02*
Y25300D01*
G01X1456540D02*
Y12800D01*
G01Y14675D02*
X1455920Y13633D01*
X1454990Y13008D01*
X1453905Y12800D01*
X1452665Y13217D01*
X1451735Y14258D01*
X1451115Y15508D01*
X1450960Y16967D01*
X1451115Y18425D01*
X1451735Y19675D01*
X1452665Y20717D01*
X1453905Y21133D01*
X1454990Y20925D01*
X1455765Y20508D01*
X1456540Y19675D01*
G01X1466150Y21133D02*
Y12800D01*
G01Y24466D02*
X1465840Y24675D01*
Y25092D01*
X1466150Y25300D01*
X1466460Y25092D01*
Y24675D01*
X1466150Y24466D01*
G01X1476380Y12800D02*
Y21133D01*
G01Y19467D02*
X1477155Y20300D01*
X1477930Y20925D01*
X1479015Y21133D01*
X1479790Y20925D01*
X1480720Y20300D01*
G01X1488625Y18425D02*
X1493585D01*
X1493120Y19883D01*
X1492345Y20717D01*
X1491260Y21133D01*
X1490175Y20925D01*
X1489245Y20300D01*
X1488625Y18842D01*
X1488315Y17591D01*
Y16342D01*
X1488625Y15092D01*
X1489400Y13841D01*
X1490330Y13008D01*
X1491415Y12800D01*
X1492500Y13217D01*
X1493585Y14466D01*
G01X1505830Y20092D02*
X1504745Y20925D01*
X1503815Y21133D01*
X1502575Y20717D01*
X1501645Y19883D01*
X1501025Y18425D01*
X1500870Y16967D01*
X1501025Y15508D01*
X1501645Y14258D01*
X1502575Y13217D01*
X1503815Y12800D01*
X1504900Y13217D01*
X1505830Y14050D01*
G01X1515750Y25300D02*
Y12800D01*
G01X1513580Y21133D02*
X1517920D01*
G01X1528150D02*
Y12800D01*
G01Y24466D02*
X1527840Y24675D01*
Y25092D01*
X1528150Y25300D01*
X1528460Y25092D01*
Y24675D01*
X1528150Y24466D01*
G01X1540550Y12800D02*
X1539620Y13008D01*
X1538690Y13841D01*
X1538070Y15300D01*
X1537760Y16967D01*
X1538070Y18633D01*
X1538690Y20092D01*
X1539620Y20925D01*
X1540550Y21133D01*
X1541480Y20925D01*
X1542410Y20092D01*
X1543030Y18633D01*
X1543185Y16967D01*
X1543030Y15300D01*
X1542410Y13841D01*
X1541480Y13008D01*
X1540550Y12800D01*
G01X1550315D02*
Y21133D01*
G01Y19050D02*
X1550935Y20092D01*
X1551865Y20925D01*
X1553105Y21133D01*
X1554190Y20925D01*
X1555120Y20092D01*
X1555585Y18633D01*
Y12800D01*
G01X903500Y42800D02*
Y545500D01*
X1387100D01*
Y42800D01*
X903500D01*
G01Y70900D02*
X1387100D01*
G01X903500Y99000D02*
X1387100D01*
G01X903500Y127100D02*
X1387100D01*
G01X903500Y155200D02*
X1387100D01*
G01X903500Y183300D02*
X1387100D01*
G01X903500Y211400D02*
X1387100D01*
G01X903500Y239500D02*
X1387100D01*
G01X903500Y267600D02*
X1387100D01*
G01X903500Y295700D02*
X1387100D01*
G01X903500Y323800D02*
X1387100D01*
G01X903500Y351900D02*
X1387100D01*
G01X903500Y380000D02*
X1387100D01*
G01X903500Y408100D02*
X1387100D01*
G01X903500Y436200D02*
X1387100D01*
G01X903500Y464300D02*
X1387100D01*
G01X903500Y492400D02*
X1387100D01*
G01X903500Y520500D02*
X1387100D01*
G01X914505Y473650D02*
Y486150D01*
X920395D01*
G01X918225Y480108D02*
X914505D01*
G01X927990Y486150D02*
X931710D01*
G01X929850D02*
Y473650D01*
G01X927990D02*
X931710D01*
G01X943180Y479900D02*
X946280D01*
Y476150D01*
X945350Y474900D01*
X944265Y474067D01*
X942715Y473650D01*
X941165Y474067D01*
X940080Y474900D01*
X939150Y476150D01*
X938530Y477608D01*
X938220Y479275D01*
Y480733D01*
X938530Y481983D01*
X939150Y483442D01*
X940080Y484692D01*
X941010Y485525D01*
X942250Y486150D01*
X943335D01*
X944575Y485733D01*
X945505Y484900D01*
G01X951240Y486150D02*
Y477192D01*
X951860Y475316D01*
X953100Y474067D01*
X954650Y473650D01*
X956200Y474067D01*
X957440Y475316D01*
X958060Y477192D01*
Y486150D01*
G01X963950Y473650D02*
Y486150D01*
X967825D01*
X969065Y485525D01*
X969840Y484692D01*
X970150Y483025D01*
X969840Y481358D01*
X968910Y480317D01*
X967825Y479692D01*
X963950D01*
G01X967825D02*
X970150Y473650D01*
G01X982550D02*
X976350D01*
Y486150D01*
X982550D01*
G01X980070Y480108D02*
X976350D01*
G01X943619Y-110365D02*
X944711Y-112115D01*
X946021Y-113282D01*
X947549Y-113865D01*
X949296Y-113282D01*
X950606Y-112115D01*
X951916Y-110365D01*
X952353Y-108032D01*
Y-96365D01*
G01X965486Y-113865D02*
X963739Y-113573D01*
X962211Y-112407D01*
X960901Y-110657D01*
X960027Y-108615D01*
X959591Y-106282D01*
Y-103948D01*
X960027Y-101615D01*
X960901Y-99573D01*
X962211Y-97824D01*
X963739Y-96657D01*
X965486Y-96365D01*
X967232Y-96657D01*
X968761Y-97824D01*
X970071Y-99573D01*
X970945Y-101615D01*
X971381Y-103948D01*
Y-106282D01*
X970945Y-108615D01*
X970071Y-110657D01*
X968761Y-112407D01*
X967232Y-113573D01*
X965486Y-113865D01*
G01X978401Y-111532D02*
X980148Y-112990D01*
X982113Y-113865D01*
X983859D01*
X985606Y-112990D01*
X986916Y-111532D01*
X987571Y-109490D01*
X987134Y-107449D01*
X986043Y-105698D01*
X984078Y-104532D01*
X981458Y-103948D01*
X979929Y-102782D01*
X979274Y-100740D01*
X979711Y-98698D01*
X980803Y-97240D01*
X982331Y-96365D01*
X983859D01*
X985388Y-96948D01*
X986698Y-98407D01*
G01X1004853Y-113865D02*
X996119D01*
Y-96365D01*
X1004853D01*
G01X1001359Y-104823D02*
X996119D01*
G01X1013619Y-113865D02*
Y-96365D01*
X1018859D01*
X1020606Y-97240D01*
X1021916Y-99282D01*
X1022353Y-101615D01*
X1021916Y-103948D01*
X1020824Y-105698D01*
X1018859Y-106574D01*
X1013619D01*
G01X1030901Y-113865D02*
Y-96365D01*
G01X1040071D02*
Y-113865D01*
G01Y-105115D02*
X1030901D01*
G01X1066119Y-96365D02*
Y-113865D01*
X1074853D01*
G01X1082527D02*
X1087986Y-96365D01*
X1093445Y-113865D01*
G01X1091479Y-107740D02*
X1084492D01*
G01X1100683Y-96365D02*
Y-108907D01*
X1101556Y-111532D01*
X1103303Y-113282D01*
X1105486Y-113865D01*
X1107669Y-113282D01*
X1109416Y-111532D01*
X1110289Y-108907D01*
Y-96365D01*
G01X960683Y-68865D02*
Y-51365D01*
X965049D01*
X966796Y-52240D01*
X968106Y-53407D01*
X969198Y-55156D01*
X970071Y-57199D01*
X970289Y-60115D01*
X970071Y-63032D01*
X969198Y-65074D01*
X968106Y-66824D01*
X966796Y-67990D01*
X965049Y-68865D01*
X960683D01*
G01X979711Y-60990D02*
X986698D01*
X986043Y-58948D01*
X984951Y-57782D01*
X983423Y-57199D01*
X981894Y-57490D01*
X980584Y-58365D01*
X979711Y-60407D01*
X979274Y-62157D01*
Y-63907D01*
X979711Y-65657D01*
X980803Y-67407D01*
X982113Y-68573D01*
X983641Y-68865D01*
X985169Y-68282D01*
X986698Y-66532D01*
G01X997211Y-66824D02*
X998303Y-67990D01*
X999831Y-68865D01*
X1001141D01*
X1002451Y-68282D01*
X1003324Y-67407D01*
X1003761Y-66241D01*
X1003543Y-64490D01*
X1002669Y-63615D01*
X998739Y-61865D01*
X997866Y-59823D01*
X998303Y-58365D01*
X999176Y-57490D01*
X1000486Y-57199D01*
X1001796Y-57490D01*
X1003106Y-58365D01*
G01X1017986Y-57199D02*
Y-68865D01*
G01Y-52532D02*
X1017549Y-52240D01*
Y-51657D01*
X1017986Y-51365D01*
X1018423Y-51657D01*
Y-52240D01*
X1017986Y-52532D01*
G01X1032429Y-73240D02*
X1033958Y-74407D01*
X1035704Y-74698D01*
X1037232Y-74407D01*
X1038543Y-72949D01*
X1039416Y-70907D01*
Y-57199D01*
G01Y-59532D02*
X1038543Y-58365D01*
X1037232Y-57490D01*
X1035704Y-57199D01*
X1033958Y-57782D01*
X1032866Y-58948D01*
X1031992Y-60990D01*
X1031556Y-63032D01*
X1031774Y-64782D01*
X1032648Y-66824D01*
X1033958Y-68282D01*
X1035704Y-68865D01*
X1037014Y-68573D01*
X1038543Y-67407D01*
X1039416Y-66241D01*
G01X1049274Y-68865D02*
Y-57199D01*
G01Y-60115D02*
X1050148Y-58657D01*
X1051458Y-57490D01*
X1053204Y-57199D01*
X1054732Y-57490D01*
X1056043Y-58657D01*
X1056698Y-60698D01*
Y-68865D01*
G01X1067211Y-60990D02*
X1074198D01*
X1073543Y-58948D01*
X1072451Y-57782D01*
X1070923Y-57199D01*
X1069394Y-57490D01*
X1068084Y-58365D01*
X1067211Y-60407D01*
X1066774Y-62157D01*
Y-63907D01*
X1067211Y-65657D01*
X1068303Y-67407D01*
X1069613Y-68573D01*
X1071141Y-68865D01*
X1072669Y-68282D01*
X1074198Y-66532D01*
G01X1084929Y-68865D02*
Y-57199D01*
G01Y-59532D02*
X1086021Y-58365D01*
X1087113Y-57490D01*
X1088641Y-57199D01*
X1089732Y-57490D01*
X1091043Y-58365D01*
G01X986890Y526750D02*
Y539250D01*
X989990D01*
X991230Y538625D01*
X992160Y537792D01*
X992935Y536542D01*
X993555Y535083D01*
X993710Y533000D01*
X993555Y530917D01*
X992935Y529458D01*
X992160Y528208D01*
X991230Y527375D01*
X989990Y526750D01*
X986890D01*
G01X999600D02*
Y539250D01*
X1003475D01*
X1004715Y538625D01*
X1005490Y537792D01*
X1005800Y536125D01*
X1005490Y534458D01*
X1004560Y533417D01*
X1003475Y532792D01*
X999600D01*
G01X1003475D02*
X1005800Y526750D01*
G01X1013240Y539250D02*
X1016960D01*
G01X1015100D02*
Y526750D01*
G01X1013240D02*
X1016960D01*
G01X1024400Y539250D02*
Y526750D01*
X1030600D01*
G01X1036800Y539250D02*
Y526750D01*
X1043000D01*
G01X1068110Y538208D02*
X1067180Y538833D01*
X1066095Y539250D01*
X1064855D01*
X1063460Y538625D01*
X1062375Y537583D01*
X1061600Y536333D01*
X1060980Y534250D01*
X1060825Y532375D01*
X1061135Y530500D01*
X1061600Y529250D01*
X1062530Y528000D01*
X1063615Y527167D01*
X1064700Y526750D01*
X1065785D01*
X1066870Y527167D01*
X1067800Y527791D01*
X1068575Y528625D01*
G01X1073845Y526750D02*
Y539250D01*
G01X1080355D02*
Y526750D01*
G01Y533000D02*
X1073845D01*
G01X1085625Y526750D02*
X1089500Y539250D01*
X1093375Y526750D01*
G01X1091980Y531125D02*
X1087020D01*
G01X1098800Y526750D02*
Y539250D01*
X1102675D01*
X1103915Y538625D01*
X1104690Y537792D01*
X1105000Y536125D01*
X1104690Y534458D01*
X1103760Y533417D01*
X1102675Y532792D01*
X1098800D01*
G01X1102675D02*
X1105000Y526750D01*
G01X1114300Y539250D02*
Y526750D01*
G01X1110735Y539250D02*
X1117865D01*
G01X1126700Y526333D02*
X1126390Y526542D01*
Y526958D01*
X1126700Y527167D01*
X1127010Y526958D01*
Y526542D01*
X1126700Y526333D01*
G01Y531958D02*
X1126390Y532167D01*
Y532583D01*
X1126700Y532792D01*
X1127010Y532583D01*
Y532167D01*
X1126700Y531958D01*
G01X1151500Y539250D02*
Y526750D01*
G01X1147935Y539250D02*
X1155065D01*
G01X1163900Y526750D02*
X1162660Y526958D01*
X1161575Y527791D01*
X1160645Y529042D01*
X1160025Y530500D01*
X1159715Y532167D01*
Y533833D01*
X1160025Y535500D01*
X1160645Y536958D01*
X1161575Y538208D01*
X1162660Y539042D01*
X1163900Y539250D01*
X1165140Y539042D01*
X1166225Y538208D01*
X1167155Y536958D01*
X1167775Y535500D01*
X1168085Y533833D01*
Y532167D01*
X1167775Y530500D01*
X1167155Y529042D01*
X1166225Y527791D01*
X1165140Y526958D01*
X1163900Y526750D01*
G01X1173200D02*
Y539250D01*
X1176920D01*
X1178160Y538625D01*
X1179090Y537167D01*
X1179400Y535500D01*
X1179090Y533833D01*
X1178315Y532583D01*
X1176920Y531958D01*
X1173200D01*
G01X1201100Y539250D02*
Y526750D01*
G01X1198930Y535083D02*
X1203270D01*
G01X1213500Y526750D02*
X1212570Y526958D01*
X1211640Y527791D01*
X1211020Y529250D01*
X1210710Y530917D01*
X1211020Y532583D01*
X1211640Y534042D01*
X1212570Y534875D01*
X1213500Y535083D01*
X1214430Y534875D01*
X1215360Y534042D01*
X1215980Y532583D01*
X1216135Y530917D01*
X1215980Y529250D01*
X1215360Y527791D01*
X1214430Y526958D01*
X1213500Y526750D01*
G01X1239540Y533417D02*
X1240160Y534042D01*
X1240625Y535083D01*
X1240935Y536542D01*
X1240625Y537792D01*
X1240005Y538625D01*
X1238920Y539250D01*
X1234735D01*
Y526750D01*
X1239850D01*
X1240935Y527583D01*
X1241555Y528833D01*
X1241865Y530292D01*
X1241555Y531750D01*
X1240625Y533000D01*
X1239540Y533417D01*
X1234735D01*
G01X1250700Y526750D02*
X1249460Y526958D01*
X1248375Y527791D01*
X1247445Y529042D01*
X1246825Y530500D01*
X1246515Y532167D01*
Y533833D01*
X1246825Y535500D01*
X1247445Y536958D01*
X1248375Y538208D01*
X1249460Y539042D01*
X1250700Y539250D01*
X1251940Y539042D01*
X1253025Y538208D01*
X1253955Y536958D01*
X1254575Y535500D01*
X1254885Y533833D01*
Y532167D01*
X1254575Y530500D01*
X1253955Y529042D01*
X1253025Y527791D01*
X1251940Y526958D01*
X1250700Y526750D01*
G01X1263100Y539250D02*
Y526750D01*
G01X1259535Y539250D02*
X1266665D01*
G01X1275500D02*
Y526750D01*
G01X1271935Y539250D02*
X1279065D01*
G01X1287900Y526750D02*
X1286660Y526958D01*
X1285575Y527791D01*
X1284645Y529042D01*
X1284025Y530500D01*
X1283715Y532167D01*
Y533833D01*
X1284025Y535500D01*
X1284645Y536958D01*
X1285575Y538208D01*
X1286660Y539042D01*
X1287900Y539250D01*
X1289140Y539042D01*
X1290225Y538208D01*
X1291155Y536958D01*
X1291775Y535500D01*
X1292085Y533833D01*
Y532167D01*
X1291775Y530500D01*
X1291155Y529042D01*
X1290225Y527791D01*
X1289140Y526958D01*
X1287900Y526750D01*
G01X1296270D02*
Y539250D01*
X1300300Y528833D01*
X1304330Y539250D01*
Y526750D01*
G01X993400Y492400D02*
Y42800D01*
G01X1017425Y501750D02*
X1021300Y514250D01*
X1025175Y501750D01*
G01X1023780Y506125D02*
X1018820D01*
G01X1030600Y514250D02*
Y501750D01*
X1036800D01*
G01X1043000Y514250D02*
Y501750D01*
X1049200D01*
G01X1067490Y514250D02*
Y505292D01*
X1068110Y503416D01*
X1069350Y502167D01*
X1070900Y501750D01*
X1072450Y502167D01*
X1073690Y503416D01*
X1074310Y505292D01*
Y514250D01*
G01X1079735Y501750D02*
Y514250D01*
X1086865Y501750D01*
Y514250D01*
G01X1093840D02*
X1097560D01*
G01X1095700D02*
Y501750D01*
G01X1093840D02*
X1097560D01*
G01X1108100Y514250D02*
Y501750D01*
G01X1104535Y514250D02*
X1111665D01*
G01X1117245Y503416D02*
X1118485Y502375D01*
X1119880Y501750D01*
X1121120D01*
X1122360Y502375D01*
X1123290Y503416D01*
X1123755Y504875D01*
X1123445Y506333D01*
X1122670Y507583D01*
X1121275Y508417D01*
X1119415Y508833D01*
X1118330Y509667D01*
X1117865Y511125D01*
X1118175Y512583D01*
X1118950Y513625D01*
X1120035Y514250D01*
X1121120D01*
X1122205Y513833D01*
X1123135Y512792D01*
G01X1141425Y501750D02*
X1145300Y514250D01*
X1149175Y501750D01*
G01X1147780Y506125D02*
X1142820D01*
G01X1154600Y501750D02*
Y514250D01*
X1158475D01*
X1159715Y513625D01*
X1160490Y512792D01*
X1160800Y511125D01*
X1160490Y509458D01*
X1159560Y508417D01*
X1158475Y507792D01*
X1154600D01*
G01X1158475D02*
X1160800Y501750D01*
G01X1173200D02*
X1167000D01*
Y514250D01*
X1173200D01*
G01X1170720Y508208D02*
X1167000D01*
G01X1193040Y514250D02*
X1196760D01*
G01X1194900D02*
Y501750D01*
G01X1193040D02*
X1196760D01*
G01X1203735D02*
Y514250D01*
X1210865Y501750D01*
Y514250D01*
G01X1228070Y501750D02*
Y514250D01*
X1232100Y503833D01*
X1236130Y514250D01*
Y501750D01*
G01X1242640Y514250D02*
X1246360D01*
G01X1244500D02*
Y501750D01*
G01X1242640D02*
X1246360D01*
G01X1253800Y514250D02*
Y501750D01*
X1260000D01*
G01X1266045Y503416D02*
X1267285Y502375D01*
X1268680Y501750D01*
X1269920D01*
X1271160Y502375D01*
X1272090Y503416D01*
X1272555Y504875D01*
X1272245Y506333D01*
X1271470Y507583D01*
X1270075Y508417D01*
X1268215Y508833D01*
X1267130Y509667D01*
X1266665Y511125D01*
X1266975Y512583D01*
X1267750Y513625D01*
X1268835Y514250D01*
X1269920D01*
X1271005Y513833D01*
X1271935Y512792D01*
G01X1025950Y50600D02*
Y63100D01*
X1024090Y60600D01*
G01Y50600D02*
X1027810D01*
G01X1038350D02*
X1039435Y50808D01*
X1040675Y51433D01*
X1041450Y52475D01*
X1041760Y53933D01*
X1041450Y55391D01*
X1040520Y56642D01*
X1039125Y57267D01*
X1037575D01*
X1036645Y57683D01*
X1035870Y58725D01*
X1035560Y60183D01*
X1036025Y61642D01*
X1037110Y62683D01*
X1038350Y63100D01*
X1039590Y62683D01*
X1040675Y61642D01*
X1041140Y60183D01*
X1040830Y58725D01*
X1040055Y57683D01*
X1039125Y57267D01*
X1037575D01*
X1036180Y56642D01*
X1035250Y55391D01*
X1034940Y53933D01*
X1035250Y52475D01*
X1036025Y51433D01*
X1037265Y50808D01*
X1038350Y50600D01*
G01X1048115Y52058D02*
X1049200Y51017D01*
X1050440Y50600D01*
X1051680Y51017D01*
X1052765Y52266D01*
X1053540Y54142D01*
X1053850Y56017D01*
Y58308D01*
X1053540Y60183D01*
X1052765Y61850D01*
X1051835Y62683D01*
X1050750Y63100D01*
X1049510Y62683D01*
X1048580Y61850D01*
X1047960Y60600D01*
X1047650Y58933D01*
X1047960Y57475D01*
X1048735Y56017D01*
X1049665Y55183D01*
X1050750Y54975D01*
X1051990Y55391D01*
X1052920Y56433D01*
X1053850Y58308D01*
G01X1063150Y50183D02*
X1062840Y50392D01*
Y50808D01*
X1063150Y51017D01*
X1063460Y50808D01*
Y50392D01*
X1063150Y50183D01*
G01X1075550Y63100D02*
X1074310Y62683D01*
X1073380Y61642D01*
X1072760Y60392D01*
X1072295Y58725D01*
X1072140Y56850D01*
X1072295Y54975D01*
X1072760Y53308D01*
X1073380Y52058D01*
X1074310Y51017D01*
X1075550Y50600D01*
X1076790Y51017D01*
X1077720Y52058D01*
X1078340Y53308D01*
X1078805Y54975D01*
X1078960Y56850D01*
X1078805Y58725D01*
X1078340Y60392D01*
X1077720Y61642D01*
X1076790Y62683D01*
X1075550Y63100D01*
G01X1085625Y58933D02*
X1090275Y50600D01*
G01Y58933D02*
X1085625Y50600D01*
G01X1100350D02*
Y63100D01*
X1098490Y60600D01*
G01Y50600D02*
X1102210D01*
G01X1109805Y61017D02*
X1110735Y62266D01*
X1111820Y62892D01*
X1113060Y63100D01*
X1114610Y62683D01*
X1115695Y61642D01*
X1116005Y60392D01*
X1115850Y59141D01*
X1115230Y58100D01*
X1112130Y56017D01*
X1110735Y54558D01*
X1109805Y52475D01*
X1109495Y50600D01*
X1116005D01*
G01X1122205Y55808D02*
X1123290Y57267D01*
X1124220Y58100D01*
X1125460Y58517D01*
X1126545Y58100D01*
X1127320Y57267D01*
X1127940Y56017D01*
X1128095Y54558D01*
X1127940Y53308D01*
X1127320Y52058D01*
X1126390Y51017D01*
X1125305Y50600D01*
X1124065Y51017D01*
X1122980Y52266D01*
X1122360Y54142D01*
X1122205Y56225D01*
X1122515Y58933D01*
X1122980Y60392D01*
X1123755Y61850D01*
X1124840Y62892D01*
X1125925Y63100D01*
X1127010Y62683D01*
X1127785Y61642D01*
G01X1137550Y50183D02*
X1137240Y50392D01*
Y50808D01*
X1137550Y51017D01*
X1137860Y50808D01*
Y50392D01*
X1137550Y50183D01*
G01X1149950Y63100D02*
X1148710Y62683D01*
X1147780Y61642D01*
X1147160Y60392D01*
X1146695Y58725D01*
X1146540Y56850D01*
X1146695Y54975D01*
X1147160Y53308D01*
X1147780Y52058D01*
X1148710Y51017D01*
X1149950Y50600D01*
X1151190Y51017D01*
X1152120Y52058D01*
X1152740Y53308D01*
X1153205Y54975D01*
X1153360Y56850D01*
X1153205Y58725D01*
X1152740Y60392D01*
X1152120Y61642D01*
X1151190Y62683D01*
X1149950Y63100D01*
G01X1063150Y78700D02*
Y91200D01*
X1061290Y88700D01*
G01Y78700D02*
X1065010D01*
G01X1077410D02*
Y91200D01*
X1071675Y82242D01*
X1079425D01*
G01X1087950Y91200D02*
X1086710Y90783D01*
X1085780Y89742D01*
X1085160Y88492D01*
X1084695Y86825D01*
X1084540Y84950D01*
X1084695Y83075D01*
X1085160Y81408D01*
X1085780Y80158D01*
X1086710Y79117D01*
X1087950Y78700D01*
X1089190Y79117D01*
X1090120Y80158D01*
X1090740Y81408D01*
X1091205Y83075D01*
X1091360Y84950D01*
X1091205Y86825D01*
X1090740Y88492D01*
X1090120Y89742D01*
X1089190Y90783D01*
X1087950Y91200D01*
G01X1100350Y78283D02*
X1100040Y78492D01*
Y78908D01*
X1100350Y79117D01*
X1100660Y78908D01*
Y78492D01*
X1100350Y78283D01*
G01X1112750Y91200D02*
X1111510Y90783D01*
X1110580Y89742D01*
X1109960Y88492D01*
X1109495Y86825D01*
X1109340Y84950D01*
X1109495Y83075D01*
X1109960Y81408D01*
X1110580Y80158D01*
X1111510Y79117D01*
X1112750Y78700D01*
X1113990Y79117D01*
X1114920Y80158D01*
X1115540Y81408D01*
X1116005Y83075D01*
X1116160Y84950D01*
X1116005Y86825D01*
X1115540Y88492D01*
X1114920Y89742D01*
X1113990Y90783D01*
X1112750Y91200D01*
G01X1063150Y106800D02*
Y119300D01*
X1061290Y116800D01*
G01Y106800D02*
X1065010D01*
G01X1072605Y117217D02*
X1073535Y118466D01*
X1074620Y119092D01*
X1075860Y119300D01*
X1077410Y118883D01*
X1078495Y117842D01*
X1078805Y116592D01*
X1078650Y115341D01*
X1078030Y114300D01*
X1074930Y112217D01*
X1073535Y110758D01*
X1072605Y108675D01*
X1072295Y106800D01*
X1078805D01*
G01X1085005Y112008D02*
X1086090Y113467D01*
X1087020Y114300D01*
X1088260Y114717D01*
X1089345Y114300D01*
X1090120Y113467D01*
X1090740Y112217D01*
X1090895Y110758D01*
X1090740Y109508D01*
X1090120Y108258D01*
X1089190Y107217D01*
X1088105Y106800D01*
X1086865Y107217D01*
X1085780Y108466D01*
X1085160Y110342D01*
X1085005Y112425D01*
X1085315Y115133D01*
X1085780Y116592D01*
X1086555Y118050D01*
X1087640Y119092D01*
X1088725Y119300D01*
X1089810Y118883D01*
X1090585Y117842D01*
G01X1100350Y106383D02*
X1100040Y106592D01*
Y107008D01*
X1100350Y107217D01*
X1100660Y107008D01*
Y106592D01*
X1100350Y106383D01*
G01X1112750Y119300D02*
X1111510Y118883D01*
X1110580Y117842D01*
X1109960Y116592D01*
X1109495Y114925D01*
X1109340Y113050D01*
X1109495Y111175D01*
X1109960Y109508D01*
X1110580Y108258D01*
X1111510Y107217D01*
X1112750Y106800D01*
X1113990Y107217D01*
X1114920Y108258D01*
X1115540Y109508D01*
X1116005Y111175D01*
X1116160Y113050D01*
X1116005Y114925D01*
X1115540Y116592D01*
X1114920Y117842D01*
X1113990Y118883D01*
X1112750Y119300D01*
G01X1063150Y134900D02*
Y147400D01*
X1061290Y144900D01*
G01Y134900D02*
X1065010D01*
G01X1075550D02*
Y147400D01*
X1073690Y144900D01*
G01Y134900D02*
X1077410D01*
G01X1085315Y136358D02*
X1086400Y135317D01*
X1087640Y134900D01*
X1088880Y135317D01*
X1089965Y136566D01*
X1090740Y138442D01*
X1091050Y140317D01*
Y142608D01*
X1090740Y144483D01*
X1089965Y146150D01*
X1089035Y146983D01*
X1087950Y147400D01*
X1086710Y146983D01*
X1085780Y146150D01*
X1085160Y144900D01*
X1084850Y143233D01*
X1085160Y141775D01*
X1085935Y140317D01*
X1086865Y139483D01*
X1087950Y139275D01*
X1089190Y139691D01*
X1090120Y140733D01*
X1091050Y142608D01*
G01X1100350Y134483D02*
X1100040Y134692D01*
Y135108D01*
X1100350Y135317D01*
X1100660Y135108D01*
Y134692D01*
X1100350Y134483D01*
G01X1112750Y147400D02*
X1111510Y146983D01*
X1110580Y145942D01*
X1109960Y144692D01*
X1109495Y143025D01*
X1109340Y141150D01*
X1109495Y139275D01*
X1109960Y137608D01*
X1110580Y136358D01*
X1111510Y135317D01*
X1112750Y134900D01*
X1113990Y135317D01*
X1114920Y136358D01*
X1115540Y137608D01*
X1116005Y139275D01*
X1116160Y141150D01*
X1116005Y143025D01*
X1115540Y144692D01*
X1114920Y145942D01*
X1113990Y146983D01*
X1112750Y147400D01*
G01X1069350Y163000D02*
X1070435Y163208D01*
X1071675Y163833D01*
X1072450Y164875D01*
X1072760Y166333D01*
X1072450Y167791D01*
X1071520Y169042D01*
X1070125Y169667D01*
X1068575D01*
X1067645Y170083D01*
X1066870Y171125D01*
X1066560Y172583D01*
X1067025Y174042D01*
X1068110Y175083D01*
X1069350Y175500D01*
X1070590Y175083D01*
X1071675Y174042D01*
X1072140Y172583D01*
X1071830Y171125D01*
X1071055Y170083D01*
X1070125Y169667D01*
X1068575D01*
X1067180Y169042D01*
X1066250Y167791D01*
X1065940Y166333D01*
X1066250Y164875D01*
X1067025Y163833D01*
X1068265Y163208D01*
X1069350Y163000D01*
G01X1078805Y168208D02*
X1079890Y169667D01*
X1080820Y170500D01*
X1082060Y170917D01*
X1083145Y170500D01*
X1083920Y169667D01*
X1084540Y168417D01*
X1084695Y166958D01*
X1084540Y165708D01*
X1083920Y164458D01*
X1082990Y163417D01*
X1081905Y163000D01*
X1080665Y163417D01*
X1079580Y164666D01*
X1078960Y166542D01*
X1078805Y168625D01*
X1079115Y171333D01*
X1079580Y172792D01*
X1080355Y174250D01*
X1081440Y175292D01*
X1082525Y175500D01*
X1083610Y175083D01*
X1084385Y174042D01*
G01X1094150Y162583D02*
X1093840Y162792D01*
Y163208D01*
X1094150Y163417D01*
X1094460Y163208D01*
Y162792D01*
X1094150Y162583D01*
G01X1106550Y175500D02*
X1105310Y175083D01*
X1104380Y174042D01*
X1103760Y172792D01*
X1103295Y171125D01*
X1103140Y169250D01*
X1103295Y167375D01*
X1103760Y165708D01*
X1104380Y164458D01*
X1105310Y163417D01*
X1106550Y163000D01*
X1107790Y163417D01*
X1108720Y164458D01*
X1109340Y165708D01*
X1109805Y167375D01*
X1109960Y169250D01*
X1109805Y171125D01*
X1109340Y172792D01*
X1108720Y174042D01*
X1107790Y175083D01*
X1106550Y175500D01*
G01X1066405Y196308D02*
X1067490Y197767D01*
X1068420Y198600D01*
X1069660Y199017D01*
X1070745Y198600D01*
X1071520Y197767D01*
X1072140Y196517D01*
X1072295Y195058D01*
X1072140Y193808D01*
X1071520Y192558D01*
X1070590Y191517D01*
X1069505Y191100D01*
X1068265Y191517D01*
X1067180Y192766D01*
X1066560Y194642D01*
X1066405Y196725D01*
X1066715Y199433D01*
X1067180Y200892D01*
X1067955Y202350D01*
X1069040Y203392D01*
X1070125Y203600D01*
X1071210Y203183D01*
X1071985Y202142D01*
G01X1078340Y192975D02*
X1079270Y191933D01*
X1080355Y191308D01*
X1081750Y191100D01*
X1083145Y191517D01*
X1084230Y192350D01*
X1085005Y193808D01*
X1085160Y195475D01*
X1084850Y197142D01*
X1084075Y198183D01*
X1082990Y199017D01*
X1081905Y199225D01*
X1080820Y199017D01*
X1079425Y198183D01*
X1079890Y203600D01*
X1084075D01*
G01X1094150Y190683D02*
X1093840Y190892D01*
Y191308D01*
X1094150Y191517D01*
X1094460Y191308D01*
Y190892D01*
X1094150Y190683D01*
G01X1106550Y203600D02*
X1105310Y203183D01*
X1104380Y202142D01*
X1103760Y200892D01*
X1103295Y199225D01*
X1103140Y197350D01*
X1103295Y195475D01*
X1103760Y193808D01*
X1104380Y192558D01*
X1105310Y191517D01*
X1106550Y191100D01*
X1107790Y191517D01*
X1108720Y192558D01*
X1109340Y193808D01*
X1109805Y195475D01*
X1109960Y197350D01*
X1109805Y199225D01*
X1109340Y200892D01*
X1108720Y202142D01*
X1107790Y203183D01*
X1106550Y203600D01*
G01X1066405Y224408D02*
X1067490Y225867D01*
X1068420Y226700D01*
X1069660Y227117D01*
X1070745Y226700D01*
X1071520Y225867D01*
X1072140Y224617D01*
X1072295Y223158D01*
X1072140Y221908D01*
X1071520Y220658D01*
X1070590Y219617D01*
X1069505Y219200D01*
X1068265Y219617D01*
X1067180Y220866D01*
X1066560Y222742D01*
X1066405Y224825D01*
X1066715Y227533D01*
X1067180Y228992D01*
X1067955Y230450D01*
X1069040Y231492D01*
X1070125Y231700D01*
X1071210Y231283D01*
X1071985Y230242D01*
G01X1078340Y221700D02*
X1079270Y220241D01*
X1080510Y219408D01*
X1081905Y219200D01*
X1083145Y219408D01*
X1084385Y220450D01*
X1085160Y221700D01*
X1085315Y222950D01*
X1085005Y224408D01*
X1083920Y225450D01*
X1082835Y225867D01*
X1081440D01*
G01X1082835D02*
X1083765Y226492D01*
X1084540Y227533D01*
X1084850Y228783D01*
X1084540Y230033D01*
X1083765Y231075D01*
X1082370Y231700D01*
X1080975Y231492D01*
X1079580Y230658D01*
G01X1094150Y218783D02*
X1093840Y218992D01*
Y219408D01*
X1094150Y219617D01*
X1094460Y219408D01*
Y218992D01*
X1094150Y218783D01*
G01X1106550Y231700D02*
X1105310Y231283D01*
X1104380Y230242D01*
X1103760Y228992D01*
X1103295Y227325D01*
X1103140Y225450D01*
X1103295Y223575D01*
X1103760Y221908D01*
X1104380Y220658D01*
X1105310Y219617D01*
X1106550Y219200D01*
X1107790Y219617D01*
X1108720Y220658D01*
X1109340Y221908D01*
X1109805Y223575D01*
X1109960Y225450D01*
X1109805Y227325D01*
X1109340Y228992D01*
X1108720Y230242D01*
X1107790Y231283D01*
X1106550Y231700D01*
G01X1071210Y247300D02*
Y259800D01*
X1065475Y250842D01*
X1073225D01*
G01X1083610Y247300D02*
Y259800D01*
X1077875Y250842D01*
X1085625D01*
G01X1094150Y246883D02*
X1093840Y247092D01*
Y247508D01*
X1094150Y247717D01*
X1094460Y247508D01*
Y247092D01*
X1094150Y246883D01*
G01X1106550Y259800D02*
X1105310Y259383D01*
X1104380Y258342D01*
X1103760Y257092D01*
X1103295Y255425D01*
X1103140Y253550D01*
X1103295Y251675D01*
X1103760Y250008D01*
X1104380Y248758D01*
X1105310Y247717D01*
X1106550Y247300D01*
X1107790Y247717D01*
X1108720Y248758D01*
X1109340Y250008D01*
X1109805Y251675D01*
X1109960Y253550D01*
X1109805Y255425D01*
X1109340Y257092D01*
X1108720Y258342D01*
X1107790Y259383D01*
X1106550Y259800D01*
G01X1071210Y275400D02*
Y287900D01*
X1065475Y278942D01*
X1073225D01*
G01X1081750Y287900D02*
X1080510Y287483D01*
X1079580Y286442D01*
X1078960Y285192D01*
X1078495Y283525D01*
X1078340Y281650D01*
X1078495Y279775D01*
X1078960Y278108D01*
X1079580Y276858D01*
X1080510Y275817D01*
X1081750Y275400D01*
X1082990Y275817D01*
X1083920Y276858D01*
X1084540Y278108D01*
X1085005Y279775D01*
X1085160Y281650D01*
X1085005Y283525D01*
X1084540Y285192D01*
X1083920Y286442D01*
X1082990Y287483D01*
X1081750Y287900D01*
G01X1094150Y274983D02*
X1093840Y275192D01*
Y275608D01*
X1094150Y275817D01*
X1094460Y275608D01*
Y275192D01*
X1094150Y274983D01*
G01X1106550Y287900D02*
X1105310Y287483D01*
X1104380Y286442D01*
X1103760Y285192D01*
X1103295Y283525D01*
X1103140Y281650D01*
X1103295Y279775D01*
X1103760Y278108D01*
X1104380Y276858D01*
X1105310Y275817D01*
X1106550Y275400D01*
X1107790Y275817D01*
X1108720Y276858D01*
X1109340Y278108D01*
X1109805Y279775D01*
X1109960Y281650D01*
X1109805Y283525D01*
X1109340Y285192D01*
X1108720Y286442D01*
X1107790Y287483D01*
X1106550Y287900D01*
G01X1071210Y303500D02*
Y316000D01*
X1065475Y307042D01*
X1073225D01*
G01X1083610Y303500D02*
Y316000D01*
X1077875Y307042D01*
X1085625D01*
G01X1094150Y303083D02*
X1093840Y303292D01*
Y303708D01*
X1094150Y303917D01*
X1094460Y303708D01*
Y303292D01*
X1094150Y303083D01*
G01X1106550Y316000D02*
X1105310Y315583D01*
X1104380Y314542D01*
X1103760Y313292D01*
X1103295Y311625D01*
X1103140Y309750D01*
X1103295Y307875D01*
X1103760Y306208D01*
X1104380Y304958D01*
X1105310Y303917D01*
X1106550Y303500D01*
X1107790Y303917D01*
X1108720Y304958D01*
X1109340Y306208D01*
X1109805Y307875D01*
X1109960Y309750D01*
X1109805Y311625D01*
X1109340Y313292D01*
X1108720Y314542D01*
X1107790Y315583D01*
X1106550Y316000D01*
G01X1071210Y331600D02*
Y344100D01*
X1065475Y335142D01*
X1073225D01*
G01X1081750Y344100D02*
X1080510Y343683D01*
X1079580Y342642D01*
X1078960Y341392D01*
X1078495Y339725D01*
X1078340Y337850D01*
X1078495Y335975D01*
X1078960Y334308D01*
X1079580Y333058D01*
X1080510Y332017D01*
X1081750Y331600D01*
X1082990Y332017D01*
X1083920Y333058D01*
X1084540Y334308D01*
X1085005Y335975D01*
X1085160Y337850D01*
X1085005Y339725D01*
X1084540Y341392D01*
X1083920Y342642D01*
X1082990Y343683D01*
X1081750Y344100D01*
G01X1094150Y331183D02*
X1093840Y331392D01*
Y331808D01*
X1094150Y332017D01*
X1094460Y331808D01*
Y331392D01*
X1094150Y331183D01*
G01X1106550Y344100D02*
X1105310Y343683D01*
X1104380Y342642D01*
X1103760Y341392D01*
X1103295Y339725D01*
X1103140Y337850D01*
X1103295Y335975D01*
X1103760Y334308D01*
X1104380Y333058D01*
X1105310Y332017D01*
X1106550Y331600D01*
X1107790Y332017D01*
X1108720Y333058D01*
X1109340Y334308D01*
X1109805Y335975D01*
X1109960Y337850D01*
X1109805Y339725D01*
X1109340Y341392D01*
X1108720Y342642D01*
X1107790Y343683D01*
X1106550Y344100D01*
G01X1069350Y359700D02*
Y372200D01*
X1067490Y369700D01*
G01Y359700D02*
X1071210D01*
G01X1078805Y364908D02*
X1079890Y366367D01*
X1080820Y367200D01*
X1082060Y367617D01*
X1083145Y367200D01*
X1083920Y366367D01*
X1084540Y365117D01*
X1084695Y363658D01*
X1084540Y362408D01*
X1083920Y361158D01*
X1082990Y360117D01*
X1081905Y359700D01*
X1080665Y360117D01*
X1079580Y361366D01*
X1078960Y363242D01*
X1078805Y365325D01*
X1079115Y368033D01*
X1079580Y369492D01*
X1080355Y370950D01*
X1081440Y371992D01*
X1082525Y372200D01*
X1083610Y371783D01*
X1084385Y370742D01*
G01X1094150Y359283D02*
X1093840Y359492D01*
Y359908D01*
X1094150Y360117D01*
X1094460Y359908D01*
Y359492D01*
X1094150Y359283D01*
G01X1106550Y372200D02*
X1105310Y371783D01*
X1104380Y370742D01*
X1103760Y369492D01*
X1103295Y367825D01*
X1103140Y365950D01*
X1103295Y364075D01*
X1103760Y362408D01*
X1104380Y361158D01*
X1105310Y360117D01*
X1106550Y359700D01*
X1107790Y360117D01*
X1108720Y361158D01*
X1109340Y362408D01*
X1109805Y364075D01*
X1109960Y365950D01*
X1109805Y367825D01*
X1109340Y369492D01*
X1108720Y370742D01*
X1107790Y371783D01*
X1106550Y372200D01*
G01X1069350Y387800D02*
Y400300D01*
X1067490Y397800D01*
G01Y387800D02*
X1071210D01*
G01X1078805Y398217D02*
X1079735Y399466D01*
X1080820Y400092D01*
X1082060Y400300D01*
X1083610Y399883D01*
X1084695Y398842D01*
X1085005Y397592D01*
X1084850Y396341D01*
X1084230Y395300D01*
X1081130Y393217D01*
X1079735Y391758D01*
X1078805Y389675D01*
X1078495Y387800D01*
X1085005D01*
G01X1094150Y387383D02*
X1093840Y387592D01*
Y388008D01*
X1094150Y388217D01*
X1094460Y388008D01*
Y387592D01*
X1094150Y387383D01*
G01X1106550Y400300D02*
X1105310Y399883D01*
X1104380Y398842D01*
X1103760Y397592D01*
X1103295Y395925D01*
X1103140Y394050D01*
X1103295Y392175D01*
X1103760Y390508D01*
X1104380Y389258D01*
X1105310Y388217D01*
X1106550Y387800D01*
X1107790Y388217D01*
X1108720Y389258D01*
X1109340Y390508D01*
X1109805Y392175D01*
X1109960Y394050D01*
X1109805Y395925D01*
X1109340Y397592D01*
X1108720Y398842D01*
X1107790Y399883D01*
X1106550Y400300D01*
G01X1069350Y415900D02*
Y428400D01*
X1067490Y425900D01*
G01Y415900D02*
X1071210D01*
G01X1081750Y428400D02*
X1080510Y427983D01*
X1079580Y426942D01*
X1078960Y425692D01*
X1078495Y424025D01*
X1078340Y422150D01*
X1078495Y420275D01*
X1078960Y418608D01*
X1079580Y417358D01*
X1080510Y416317D01*
X1081750Y415900D01*
X1082990Y416317D01*
X1083920Y417358D01*
X1084540Y418608D01*
X1085005Y420275D01*
X1085160Y422150D01*
X1085005Y424025D01*
X1084540Y425692D01*
X1083920Y426942D01*
X1082990Y427983D01*
X1081750Y428400D01*
G01X1094150Y415483D02*
X1093840Y415692D01*
Y416108D01*
X1094150Y416317D01*
X1094460Y416108D01*
Y415692D01*
X1094150Y415483D01*
G01X1106550Y428400D02*
X1105310Y427983D01*
X1104380Y426942D01*
X1103760Y425692D01*
X1103295Y424025D01*
X1103140Y422150D01*
X1103295Y420275D01*
X1103760Y418608D01*
X1104380Y417358D01*
X1105310Y416317D01*
X1106550Y415900D01*
X1107790Y416317D01*
X1108720Y417358D01*
X1109340Y418608D01*
X1109805Y420275D01*
X1109960Y422150D01*
X1109805Y424025D01*
X1109340Y425692D01*
X1108720Y426942D01*
X1107790Y427983D01*
X1106550Y428400D01*
G01X1066095Y475316D02*
X1067335Y474275D01*
X1068730Y473650D01*
X1069970D01*
X1071210Y474275D01*
X1072140Y475316D01*
X1072605Y476775D01*
X1072295Y478233D01*
X1071520Y479483D01*
X1070125Y480317D01*
X1068265Y480733D01*
X1067180Y481567D01*
X1066715Y483025D01*
X1067025Y484483D01*
X1067800Y485525D01*
X1068885Y486150D01*
X1069970D01*
X1071055Y485733D01*
X1071985Y484692D01*
G01X1079890Y486150D02*
X1083610D01*
G01X1081750D02*
Y473650D01*
G01X1079890D02*
X1083610D01*
G01X1091205Y486150D02*
X1097095D01*
X1091205Y473650D01*
X1097095D01*
G01X1109650D02*
X1103450D01*
Y486150D01*
X1109650D01*
G01X1107170Y480108D02*
X1103450D01*
G01X1075550Y444000D02*
X1076635Y444208D01*
X1077875Y444833D01*
X1078650Y445875D01*
X1078960Y447333D01*
X1078650Y448791D01*
X1077720Y450042D01*
X1076325Y450667D01*
X1074775D01*
X1073845Y451083D01*
X1073070Y452125D01*
X1072760Y453583D01*
X1073225Y455042D01*
X1074310Y456083D01*
X1075550Y456500D01*
X1076790Y456083D01*
X1077875Y455042D01*
X1078340Y453583D01*
X1078030Y452125D01*
X1077255Y451083D01*
X1076325Y450667D01*
X1074775D01*
X1073380Y450042D01*
X1072450Y448791D01*
X1072140Y447333D01*
X1072450Y445875D01*
X1073225Y444833D01*
X1074465Y444208D01*
X1075550Y444000D01*
G01X1087950Y443583D02*
X1087640Y443792D01*
Y444208D01*
X1087950Y444417D01*
X1088260Y444208D01*
Y443792D01*
X1087950Y443583D01*
G01X1100350Y456500D02*
X1099110Y456083D01*
X1098180Y455042D01*
X1097560Y453792D01*
X1097095Y452125D01*
X1096940Y450250D01*
X1097095Y448375D01*
X1097560Y446708D01*
X1098180Y445458D01*
X1099110Y444417D01*
X1100350Y444000D01*
X1101590Y444417D01*
X1102520Y445458D01*
X1103140Y446708D01*
X1103605Y448375D01*
X1103760Y450250D01*
X1103605Y452125D01*
X1103140Y453792D01*
X1102520Y455042D01*
X1101590Y456083D01*
X1100350Y456500D01*
G01X1131686Y-113865D02*
Y-96365D01*
X1129066Y-99865D01*
G01Y-113865D02*
X1134306D01*
G01X1149186D02*
Y-96365D01*
X1146566Y-99865D01*
G01Y-113865D02*
X1151806D01*
G01X1162756Y-114448D02*
X1170616Y-96365D01*
G01X1184186Y-113865D02*
Y-96365D01*
X1181566Y-99865D01*
G01Y-113865D02*
X1186806D01*
G01X1196883Y-110365D02*
X1198192Y-112407D01*
X1199939Y-113573D01*
X1201904Y-113865D01*
X1203651Y-113573D01*
X1205398Y-112115D01*
X1206489Y-110365D01*
X1206708Y-108615D01*
X1206271Y-106574D01*
X1204743Y-105115D01*
X1203214Y-104532D01*
X1201249D01*
G01X1203214D02*
X1204524Y-103657D01*
X1205616Y-102199D01*
X1206053Y-100449D01*
X1205616Y-98698D01*
X1204524Y-97240D01*
X1202559Y-96365D01*
X1200594Y-96657D01*
X1198629Y-97824D01*
G01X1215256Y-114448D02*
X1223116Y-96365D01*
G01X1232538Y-99282D02*
X1233848Y-97532D01*
X1235376Y-96657D01*
X1237123Y-96365D01*
X1239306Y-96948D01*
X1240834Y-98407D01*
X1241271Y-100156D01*
X1241053Y-101907D01*
X1240179Y-103365D01*
X1235813Y-106282D01*
X1233848Y-108323D01*
X1232538Y-111241D01*
X1232101Y-113865D01*
X1241271D01*
G01X1254186Y-96365D02*
X1252439Y-96948D01*
X1251129Y-98407D01*
X1250256Y-100156D01*
X1249601Y-102490D01*
X1249383Y-105115D01*
X1249601Y-107740D01*
X1250256Y-110074D01*
X1251129Y-111824D01*
X1252439Y-113282D01*
X1254186Y-113865D01*
X1255932Y-113282D01*
X1257243Y-111824D01*
X1258116Y-110074D01*
X1258771Y-107740D01*
X1258989Y-105115D01*
X1258771Y-102490D01*
X1258116Y-100156D01*
X1257243Y-98407D01*
X1255932Y-96948D01*
X1254186Y-96365D01*
G01X1271686Y-113865D02*
Y-96365D01*
X1269066Y-99865D01*
G01Y-113865D02*
X1274306D01*
G01X1291806D02*
Y-96365D01*
X1283727Y-108907D01*
X1294645D01*
G01X1179383Y-68865D02*
Y-51365D01*
X1183749D01*
X1185496Y-52240D01*
X1186806Y-53407D01*
X1187898Y-55156D01*
X1188771Y-57199D01*
X1188989Y-60115D01*
X1188771Y-63032D01*
X1187898Y-65074D01*
X1186806Y-66824D01*
X1185496Y-67990D01*
X1183749Y-68865D01*
X1179383D01*
G01X1205616D02*
Y-57199D01*
G01Y-59240D02*
X1204743Y-58074D01*
X1203432Y-57490D01*
X1201904Y-57199D01*
X1200376Y-57782D01*
X1199066Y-58948D01*
X1198192Y-60698D01*
X1197756Y-63032D01*
X1198192Y-65365D01*
X1199066Y-67115D01*
X1200376Y-68282D01*
X1201904Y-68865D01*
X1203432Y-68573D01*
X1204743Y-67699D01*
X1205616Y-66532D01*
G01X1219186Y-51365D02*
Y-68865D01*
G01X1216129Y-57199D02*
X1222243D01*
G01X1233411Y-60990D02*
X1240398D01*
X1239743Y-58948D01*
X1238651Y-57782D01*
X1237123Y-57199D01*
X1235594Y-57490D01*
X1234284Y-58365D01*
X1233411Y-60407D01*
X1232974Y-62157D01*
Y-63907D01*
X1233411Y-65657D01*
X1234503Y-67407D01*
X1235813Y-68573D01*
X1237341Y-68865D01*
X1238869Y-68282D01*
X1240398Y-66532D01*
G01X1182500Y492400D02*
Y42800D01*
G01X1186685Y50600D02*
Y63100D01*
X1193815Y50600D01*
Y63100D01*
G01X1202650Y50600D02*
X1201410Y50808D01*
X1200325Y51641D01*
X1199395Y52892D01*
X1198775Y54350D01*
X1198465Y56017D01*
Y57683D01*
X1198775Y59350D01*
X1199395Y60808D01*
X1200325Y62058D01*
X1201410Y62892D01*
X1202650Y63100D01*
X1203890Y62892D01*
X1204975Y62058D01*
X1205905Y60808D01*
X1206525Y59350D01*
X1206835Y57683D01*
Y56017D01*
X1206525Y54350D01*
X1205905Y52892D01*
X1204975Y51641D01*
X1203890Y50808D01*
X1202650Y50600D01*
G01X1211485D02*
Y63100D01*
X1218615Y50600D01*
Y63100D01*
G01X1225435Y54767D02*
X1229465D01*
G01X1236750Y50600D02*
Y63100D01*
X1240470D01*
X1241710Y62475D01*
X1242640Y61017D01*
X1242950Y59350D01*
X1242640Y57683D01*
X1241865Y56433D01*
X1240470Y55808D01*
X1236750D01*
G01X1249150Y63100D02*
Y50600D01*
X1255350D01*
G01X1260775D02*
X1264650Y63100D01*
X1268525Y50600D01*
G01X1267130Y54975D02*
X1262170D01*
G01X1277050Y63100D02*
Y50600D01*
G01X1273485Y63100D02*
X1280615D01*
G01X1292550Y50600D02*
X1286350D01*
Y63100D01*
X1292550D01*
G01X1290070Y57058D02*
X1286350D01*
G01X1298440Y50600D02*
Y63100D01*
X1301540D01*
X1302780Y62475D01*
X1303710Y61642D01*
X1304485Y60392D01*
X1305105Y58933D01*
X1305260Y56850D01*
X1305105Y54767D01*
X1304485Y53308D01*
X1303710Y52058D01*
X1302780Y51225D01*
X1301540Y50600D01*
X1298440D01*
G01X1186685Y78700D02*
Y91200D01*
X1193815Y78700D01*
Y91200D01*
G01X1202650Y78700D02*
X1201410Y78908D01*
X1200325Y79741D01*
X1199395Y80992D01*
X1198775Y82450D01*
X1198465Y84117D01*
Y85783D01*
X1198775Y87450D01*
X1199395Y88908D01*
X1200325Y90158D01*
X1201410Y90992D01*
X1202650Y91200D01*
X1203890Y90992D01*
X1204975Y90158D01*
X1205905Y88908D01*
X1206525Y87450D01*
X1206835Y85783D01*
Y84117D01*
X1206525Y82450D01*
X1205905Y80992D01*
X1204975Y79741D01*
X1203890Y78908D01*
X1202650Y78700D01*
G01X1211485D02*
Y91200D01*
X1218615Y78700D01*
Y91200D01*
G01X1225435Y82867D02*
X1229465D01*
G01X1236750Y78700D02*
Y91200D01*
X1240470D01*
X1241710Y90575D01*
X1242640Y89117D01*
X1242950Y87450D01*
X1242640Y85783D01*
X1241865Y84533D01*
X1240470Y83908D01*
X1236750D01*
G01X1249150Y91200D02*
Y78700D01*
X1255350D01*
G01X1260775D02*
X1264650Y91200D01*
X1268525Y78700D01*
G01X1267130Y83075D02*
X1262170D01*
G01X1277050Y91200D02*
Y78700D01*
G01X1273485Y91200D02*
X1280615D01*
G01X1292550Y78700D02*
X1286350D01*
Y91200D01*
X1292550D01*
G01X1290070Y85158D02*
X1286350D01*
G01X1298440Y78700D02*
Y91200D01*
X1301540D01*
X1302780Y90575D01*
X1303710Y89742D01*
X1304485Y88492D01*
X1305105Y87033D01*
X1305260Y84950D01*
X1305105Y82867D01*
X1304485Y81408D01*
X1303710Y80158D01*
X1302780Y79325D01*
X1301540Y78700D01*
X1298440D01*
G01X1186685Y106800D02*
Y119300D01*
X1193815Y106800D01*
Y119300D01*
G01X1202650Y106800D02*
X1201410Y107008D01*
X1200325Y107841D01*
X1199395Y109092D01*
X1198775Y110550D01*
X1198465Y112217D01*
Y113883D01*
X1198775Y115550D01*
X1199395Y117008D01*
X1200325Y118258D01*
X1201410Y119092D01*
X1202650Y119300D01*
X1203890Y119092D01*
X1204975Y118258D01*
X1205905Y117008D01*
X1206525Y115550D01*
X1206835Y113883D01*
Y112217D01*
X1206525Y110550D01*
X1205905Y109092D01*
X1204975Y107841D01*
X1203890Y107008D01*
X1202650Y106800D01*
G01X1211485D02*
Y119300D01*
X1218615Y106800D01*
Y119300D01*
G01X1225435Y110967D02*
X1229465D01*
G01X1236750Y106800D02*
Y119300D01*
X1240470D01*
X1241710Y118675D01*
X1242640Y117217D01*
X1242950Y115550D01*
X1242640Y113883D01*
X1241865Y112633D01*
X1240470Y112008D01*
X1236750D01*
G01X1249150Y119300D02*
Y106800D01*
X1255350D01*
G01X1260775D02*
X1264650Y119300D01*
X1268525Y106800D01*
G01X1267130Y111175D02*
X1262170D01*
G01X1277050Y119300D02*
Y106800D01*
G01X1273485Y119300D02*
X1280615D01*
G01X1292550Y106800D02*
X1286350D01*
Y119300D01*
X1292550D01*
G01X1290070Y113258D02*
X1286350D01*
G01X1298440Y106800D02*
Y119300D01*
X1301540D01*
X1302780Y118675D01*
X1303710Y117842D01*
X1304485Y116592D01*
X1305105Y115133D01*
X1305260Y113050D01*
X1305105Y110967D01*
X1304485Y109508D01*
X1303710Y108258D01*
X1302780Y107425D01*
X1301540Y106800D01*
X1298440D01*
G01X1186685Y134900D02*
Y147400D01*
X1193815Y134900D01*
Y147400D01*
G01X1202650Y134900D02*
X1201410Y135108D01*
X1200325Y135941D01*
X1199395Y137192D01*
X1198775Y138650D01*
X1198465Y140317D01*
Y141983D01*
X1198775Y143650D01*
X1199395Y145108D01*
X1200325Y146358D01*
X1201410Y147192D01*
X1202650Y147400D01*
X1203890Y147192D01*
X1204975Y146358D01*
X1205905Y145108D01*
X1206525Y143650D01*
X1206835Y141983D01*
Y140317D01*
X1206525Y138650D01*
X1205905Y137192D01*
X1204975Y135941D01*
X1203890Y135108D01*
X1202650Y134900D01*
G01X1211485D02*
Y147400D01*
X1218615Y134900D01*
Y147400D01*
G01X1225435Y139067D02*
X1229465D01*
G01X1236750Y134900D02*
Y147400D01*
X1240470D01*
X1241710Y146775D01*
X1242640Y145317D01*
X1242950Y143650D01*
X1242640Y141983D01*
X1241865Y140733D01*
X1240470Y140108D01*
X1236750D01*
G01X1249150Y147400D02*
Y134900D01*
X1255350D01*
G01X1260775D02*
X1264650Y147400D01*
X1268525Y134900D01*
G01X1267130Y139275D02*
X1262170D01*
G01X1277050Y147400D02*
Y134900D01*
G01X1273485Y147400D02*
X1280615D01*
G01X1292550Y134900D02*
X1286350D01*
Y147400D01*
X1292550D01*
G01X1290070Y141358D02*
X1286350D01*
G01X1298440Y134900D02*
Y147400D01*
X1301540D01*
X1302780Y146775D01*
X1303710Y145942D01*
X1304485Y144692D01*
X1305105Y143233D01*
X1305260Y141150D01*
X1305105Y139067D01*
X1304485Y137608D01*
X1303710Y136358D01*
X1302780Y135525D01*
X1301540Y134900D01*
X1298440D01*
G01X1186685Y163000D02*
Y175500D01*
X1193815Y163000D01*
Y175500D01*
G01X1202650Y163000D02*
X1201410Y163208D01*
X1200325Y164041D01*
X1199395Y165292D01*
X1198775Y166750D01*
X1198465Y168417D01*
Y170083D01*
X1198775Y171750D01*
X1199395Y173208D01*
X1200325Y174458D01*
X1201410Y175292D01*
X1202650Y175500D01*
X1203890Y175292D01*
X1204975Y174458D01*
X1205905Y173208D01*
X1206525Y171750D01*
X1206835Y170083D01*
Y168417D01*
X1206525Y166750D01*
X1205905Y165292D01*
X1204975Y164041D01*
X1203890Y163208D01*
X1202650Y163000D01*
G01X1211485D02*
Y175500D01*
X1218615Y163000D01*
Y175500D01*
G01X1225435Y167167D02*
X1229465D01*
G01X1236750Y163000D02*
Y175500D01*
X1240470D01*
X1241710Y174875D01*
X1242640Y173417D01*
X1242950Y171750D01*
X1242640Y170083D01*
X1241865Y168833D01*
X1240470Y168208D01*
X1236750D01*
G01X1249150Y175500D02*
Y163000D01*
X1255350D01*
G01X1260775D02*
X1264650Y175500D01*
X1268525Y163000D01*
G01X1267130Y167375D02*
X1262170D01*
G01X1277050Y175500D02*
Y163000D01*
G01X1273485Y175500D02*
X1280615D01*
G01X1292550Y163000D02*
X1286350D01*
Y175500D01*
X1292550D01*
G01X1290070Y169458D02*
X1286350D01*
G01X1298440Y163000D02*
Y175500D01*
X1301540D01*
X1302780Y174875D01*
X1303710Y174042D01*
X1304485Y172792D01*
X1305105Y171333D01*
X1305260Y169250D01*
X1305105Y167167D01*
X1304485Y165708D01*
X1303710Y164458D01*
X1302780Y163625D01*
X1301540Y163000D01*
X1298440D01*
G01X1186685Y191100D02*
Y203600D01*
X1193815Y191100D01*
Y203600D01*
G01X1202650Y191100D02*
X1201410Y191308D01*
X1200325Y192141D01*
X1199395Y193392D01*
X1198775Y194850D01*
X1198465Y196517D01*
Y198183D01*
X1198775Y199850D01*
X1199395Y201308D01*
X1200325Y202558D01*
X1201410Y203392D01*
X1202650Y203600D01*
X1203890Y203392D01*
X1204975Y202558D01*
X1205905Y201308D01*
X1206525Y199850D01*
X1206835Y198183D01*
Y196517D01*
X1206525Y194850D01*
X1205905Y193392D01*
X1204975Y192141D01*
X1203890Y191308D01*
X1202650Y191100D01*
G01X1211485D02*
Y203600D01*
X1218615Y191100D01*
Y203600D01*
G01X1225435Y195267D02*
X1229465D01*
G01X1236750Y191100D02*
Y203600D01*
X1240470D01*
X1241710Y202975D01*
X1242640Y201517D01*
X1242950Y199850D01*
X1242640Y198183D01*
X1241865Y196933D01*
X1240470Y196308D01*
X1236750D01*
G01X1249150Y203600D02*
Y191100D01*
X1255350D01*
G01X1260775D02*
X1264650Y203600D01*
X1268525Y191100D01*
G01X1267130Y195475D02*
X1262170D01*
G01X1277050Y203600D02*
Y191100D01*
G01X1273485Y203600D02*
X1280615D01*
G01X1292550Y191100D02*
X1286350D01*
Y203600D01*
X1292550D01*
G01X1290070Y197558D02*
X1286350D01*
G01X1298440Y191100D02*
Y203600D01*
X1301540D01*
X1302780Y202975D01*
X1303710Y202142D01*
X1304485Y200892D01*
X1305105Y199433D01*
X1305260Y197350D01*
X1305105Y195267D01*
X1304485Y193808D01*
X1303710Y192558D01*
X1302780Y191725D01*
X1301540Y191100D01*
X1298440D01*
G01X1186685Y219200D02*
Y231700D01*
X1193815Y219200D01*
Y231700D01*
G01X1202650Y219200D02*
X1201410Y219408D01*
X1200325Y220241D01*
X1199395Y221492D01*
X1198775Y222950D01*
X1198465Y224617D01*
Y226283D01*
X1198775Y227950D01*
X1199395Y229408D01*
X1200325Y230658D01*
X1201410Y231492D01*
X1202650Y231700D01*
X1203890Y231492D01*
X1204975Y230658D01*
X1205905Y229408D01*
X1206525Y227950D01*
X1206835Y226283D01*
Y224617D01*
X1206525Y222950D01*
X1205905Y221492D01*
X1204975Y220241D01*
X1203890Y219408D01*
X1202650Y219200D01*
G01X1211485D02*
Y231700D01*
X1218615Y219200D01*
Y231700D01*
G01X1225435Y223367D02*
X1229465D01*
G01X1236750Y219200D02*
Y231700D01*
X1240470D01*
X1241710Y231075D01*
X1242640Y229617D01*
X1242950Y227950D01*
X1242640Y226283D01*
X1241865Y225033D01*
X1240470Y224408D01*
X1236750D01*
G01X1249150Y231700D02*
Y219200D01*
X1255350D01*
G01X1260775D02*
X1264650Y231700D01*
X1268525Y219200D01*
G01X1267130Y223575D02*
X1262170D01*
G01X1277050Y231700D02*
Y219200D01*
G01X1273485Y231700D02*
X1280615D01*
G01X1292550Y219200D02*
X1286350D01*
Y231700D01*
X1292550D01*
G01X1290070Y225658D02*
X1286350D01*
G01X1298440Y219200D02*
Y231700D01*
X1301540D01*
X1302780Y231075D01*
X1303710Y230242D01*
X1304485Y228992D01*
X1305105Y227533D01*
X1305260Y225450D01*
X1305105Y223367D01*
X1304485Y221908D01*
X1303710Y220658D01*
X1302780Y219825D01*
X1301540Y219200D01*
X1298440D01*
G01X1186685Y247300D02*
Y259800D01*
X1193815Y247300D01*
Y259800D01*
G01X1202650Y247300D02*
X1201410Y247508D01*
X1200325Y248341D01*
X1199395Y249592D01*
X1198775Y251050D01*
X1198465Y252717D01*
Y254383D01*
X1198775Y256050D01*
X1199395Y257508D01*
X1200325Y258758D01*
X1201410Y259592D01*
X1202650Y259800D01*
X1203890Y259592D01*
X1204975Y258758D01*
X1205905Y257508D01*
X1206525Y256050D01*
X1206835Y254383D01*
Y252717D01*
X1206525Y251050D01*
X1205905Y249592D01*
X1204975Y248341D01*
X1203890Y247508D01*
X1202650Y247300D01*
G01X1211485D02*
Y259800D01*
X1218615Y247300D01*
Y259800D01*
G01X1225435Y251467D02*
X1229465D01*
G01X1236750Y247300D02*
Y259800D01*
X1240470D01*
X1241710Y259175D01*
X1242640Y257717D01*
X1242950Y256050D01*
X1242640Y254383D01*
X1241865Y253133D01*
X1240470Y252508D01*
X1236750D01*
G01X1249150Y259800D02*
Y247300D01*
X1255350D01*
G01X1260775D02*
X1264650Y259800D01*
X1268525Y247300D01*
G01X1267130Y251675D02*
X1262170D01*
G01X1277050Y259800D02*
Y247300D01*
G01X1273485Y259800D02*
X1280615D01*
G01X1292550Y247300D02*
X1286350D01*
Y259800D01*
X1292550D01*
G01X1290070Y253758D02*
X1286350D01*
G01X1298440Y247300D02*
Y259800D01*
X1301540D01*
X1302780Y259175D01*
X1303710Y258342D01*
X1304485Y257092D01*
X1305105Y255633D01*
X1305260Y253550D01*
X1305105Y251467D01*
X1304485Y250008D01*
X1303710Y248758D01*
X1302780Y247925D01*
X1301540Y247300D01*
X1298440D01*
G01X1186685Y275400D02*
Y287900D01*
X1193815Y275400D01*
Y287900D01*
G01X1202650Y275400D02*
X1201410Y275608D01*
X1200325Y276441D01*
X1199395Y277692D01*
X1198775Y279150D01*
X1198465Y280817D01*
Y282483D01*
X1198775Y284150D01*
X1199395Y285608D01*
X1200325Y286858D01*
X1201410Y287692D01*
X1202650Y287900D01*
X1203890Y287692D01*
X1204975Y286858D01*
X1205905Y285608D01*
X1206525Y284150D01*
X1206835Y282483D01*
Y280817D01*
X1206525Y279150D01*
X1205905Y277692D01*
X1204975Y276441D01*
X1203890Y275608D01*
X1202650Y275400D01*
G01X1211485D02*
Y287900D01*
X1218615Y275400D01*
Y287900D01*
G01X1225435Y279567D02*
X1229465D01*
G01X1236750Y275400D02*
Y287900D01*
X1240470D01*
X1241710Y287275D01*
X1242640Y285817D01*
X1242950Y284150D01*
X1242640Y282483D01*
X1241865Y281233D01*
X1240470Y280608D01*
X1236750D01*
G01X1249150Y287900D02*
Y275400D01*
X1255350D01*
G01X1260775D02*
X1264650Y287900D01*
X1268525Y275400D01*
G01X1267130Y279775D02*
X1262170D01*
G01X1277050Y287900D02*
Y275400D01*
G01X1273485Y287900D02*
X1280615D01*
G01X1292550Y275400D02*
X1286350D01*
Y287900D01*
X1292550D01*
G01X1290070Y281858D02*
X1286350D01*
G01X1298440Y275400D02*
Y287900D01*
X1301540D01*
X1302780Y287275D01*
X1303710Y286442D01*
X1304485Y285192D01*
X1305105Y283733D01*
X1305260Y281650D01*
X1305105Y279567D01*
X1304485Y278108D01*
X1303710Y276858D01*
X1302780Y276025D01*
X1301540Y275400D01*
X1298440D01*
G01X1211950Y303500D02*
Y316000D01*
X1215670D01*
X1216910Y315375D01*
X1217840Y313917D01*
X1218150Y312250D01*
X1217840Y310583D01*
X1217065Y309333D01*
X1215670Y308708D01*
X1211950D01*
G01X1224350Y316000D02*
Y303500D01*
X1230550D01*
G01X1235975D02*
X1239850Y316000D01*
X1243725Y303500D01*
G01X1242330Y307875D02*
X1237370D01*
G01X1252250Y316000D02*
Y303500D01*
G01X1248685Y316000D02*
X1255815D01*
G01X1267750Y303500D02*
X1261550D01*
Y316000D01*
X1267750D01*
G01X1265270Y309958D02*
X1261550D01*
G01X1273640Y303500D02*
Y316000D01*
X1276740D01*
X1277980Y315375D01*
X1278910Y314542D01*
X1279685Y313292D01*
X1280305Y311833D01*
X1280460Y309750D01*
X1280305Y307667D01*
X1279685Y306208D01*
X1278910Y304958D01*
X1277980Y304125D01*
X1276740Y303500D01*
X1273640D01*
G01X1211950Y331600D02*
Y344100D01*
X1215670D01*
X1216910Y343475D01*
X1217840Y342017D01*
X1218150Y340350D01*
X1217840Y338683D01*
X1217065Y337433D01*
X1215670Y336808D01*
X1211950D01*
G01X1224350Y344100D02*
Y331600D01*
X1230550D01*
G01X1235975D02*
X1239850Y344100D01*
X1243725Y331600D01*
G01X1242330Y335975D02*
X1237370D01*
G01X1252250Y344100D02*
Y331600D01*
G01X1248685Y344100D02*
X1255815D01*
G01X1267750Y331600D02*
X1261550D01*
Y344100D01*
X1267750D01*
G01X1265270Y338058D02*
X1261550D01*
G01X1273640Y331600D02*
Y344100D01*
X1276740D01*
X1277980Y343475D01*
X1278910Y342642D01*
X1279685Y341392D01*
X1280305Y339933D01*
X1280460Y337850D01*
X1280305Y335767D01*
X1279685Y334308D01*
X1278910Y333058D01*
X1277980Y332225D01*
X1276740Y331600D01*
X1273640D01*
G01X1211950Y359700D02*
Y372200D01*
X1215670D01*
X1216910Y371575D01*
X1217840Y370117D01*
X1218150Y368450D01*
X1217840Y366783D01*
X1217065Y365533D01*
X1215670Y364908D01*
X1211950D01*
G01X1224350Y372200D02*
Y359700D01*
X1230550D01*
G01X1235975D02*
X1239850Y372200D01*
X1243725Y359700D01*
G01X1242330Y364075D02*
X1237370D01*
G01X1252250Y372200D02*
Y359700D01*
G01X1248685Y372200D02*
X1255815D01*
G01X1267750Y359700D02*
X1261550D01*
Y372200D01*
X1267750D01*
G01X1265270Y366158D02*
X1261550D01*
G01X1273640Y359700D02*
Y372200D01*
X1276740D01*
X1277980Y371575D01*
X1278910Y370742D01*
X1279685Y369492D01*
X1280305Y368033D01*
X1280460Y365950D01*
X1280305Y363867D01*
X1279685Y362408D01*
X1278910Y361158D01*
X1277980Y360325D01*
X1276740Y359700D01*
X1273640D01*
G01X1211950Y387800D02*
Y400300D01*
X1215670D01*
X1216910Y399675D01*
X1217840Y398217D01*
X1218150Y396550D01*
X1217840Y394883D01*
X1217065Y393633D01*
X1215670Y393008D01*
X1211950D01*
G01X1224350Y400300D02*
Y387800D01*
X1230550D01*
G01X1235975D02*
X1239850Y400300D01*
X1243725Y387800D01*
G01X1242330Y392175D02*
X1237370D01*
G01X1252250Y400300D02*
Y387800D01*
G01X1248685Y400300D02*
X1255815D01*
G01X1267750Y387800D02*
X1261550D01*
Y400300D01*
X1267750D01*
G01X1265270Y394258D02*
X1261550D01*
G01X1273640Y387800D02*
Y400300D01*
X1276740D01*
X1277980Y399675D01*
X1278910Y398842D01*
X1279685Y397592D01*
X1280305Y396133D01*
X1280460Y394050D01*
X1280305Y391967D01*
X1279685Y390508D01*
X1278910Y389258D01*
X1277980Y388425D01*
X1276740Y387800D01*
X1273640D01*
G01X1211950Y415900D02*
Y428400D01*
X1215670D01*
X1216910Y427775D01*
X1217840Y426317D01*
X1218150Y424650D01*
X1217840Y422983D01*
X1217065Y421733D01*
X1215670Y421108D01*
X1211950D01*
G01X1224350Y428400D02*
Y415900D01*
X1230550D01*
G01X1235975D02*
X1239850Y428400D01*
X1243725Y415900D01*
G01X1242330Y420275D02*
X1237370D01*
G01X1252250Y428400D02*
Y415900D01*
G01X1248685Y428400D02*
X1255815D01*
G01X1267750Y415900D02*
X1261550D01*
Y428400D01*
X1267750D01*
G01X1265270Y422358D02*
X1261550D01*
G01X1273640Y415900D02*
Y428400D01*
X1276740D01*
X1277980Y427775D01*
X1278910Y426942D01*
X1279685Y425692D01*
X1280305Y424233D01*
X1280460Y422150D01*
X1280305Y420067D01*
X1279685Y418608D01*
X1278910Y417358D01*
X1277980Y416525D01*
X1276740Y415900D01*
X1273640D01*
G01X1211950Y444000D02*
Y456500D01*
X1215670D01*
X1216910Y455875D01*
X1217840Y454417D01*
X1218150Y452750D01*
X1217840Y451083D01*
X1217065Y449833D01*
X1215670Y449208D01*
X1211950D01*
G01X1224350Y456500D02*
Y444000D01*
X1230550D01*
G01X1235975D02*
X1239850Y456500D01*
X1243725Y444000D01*
G01X1242330Y448375D02*
X1237370D01*
G01X1252250Y456500D02*
Y444000D01*
G01X1248685Y456500D02*
X1255815D01*
G01X1267750Y444000D02*
X1261550D01*
Y456500D01*
X1267750D01*
G01X1265270Y450458D02*
X1261550D01*
G01X1273640Y444000D02*
Y456500D01*
X1276740D01*
X1277980Y455875D01*
X1278910Y455042D01*
X1279685Y453792D01*
X1280305Y452333D01*
X1280460Y450250D01*
X1280305Y448167D01*
X1279685Y446708D01*
X1278910Y445458D01*
X1277980Y444625D01*
X1276740Y444000D01*
X1273640D01*
G01X1211950Y473650D02*
Y486150D01*
X1215670D01*
X1216910Y485525D01*
X1217840Y484067D01*
X1218150Y482400D01*
X1217840Y480733D01*
X1217065Y479483D01*
X1215670Y478858D01*
X1211950D01*
G01X1224350Y486150D02*
Y473650D01*
X1230550D01*
G01X1235975D02*
X1239850Y486150D01*
X1243725Y473650D01*
G01X1242330Y478025D02*
X1237370D01*
G01X1252250Y486150D02*
Y473650D01*
G01X1248685Y486150D02*
X1255815D01*
G01X1267750Y473650D02*
X1261550D01*
Y486150D01*
X1267750D01*
G01X1265270Y480108D02*
X1261550D01*
G01X1273640Y473650D02*
Y486150D01*
X1276740D01*
X1277980Y485525D01*
X1278910Y484692D01*
X1279685Y483442D01*
X1280305Y481983D01*
X1280460Y479900D01*
X1280305Y477817D01*
X1279685Y476358D01*
X1278910Y475108D01*
X1277980Y474275D01*
X1276740Y473650D01*
X1273640D01*
G01X1309600Y492400D02*
Y42800D01*
G01X1329750Y415900D02*
Y428400D01*
X1327890Y425900D01*
G01Y415900D02*
X1331610D01*
G01X1342150D02*
Y428400D01*
X1340290Y425900D01*
G01Y415900D02*
X1344010D01*
G01X1351140Y417775D02*
X1352070Y416733D01*
X1353155Y416108D01*
X1354550Y415900D01*
X1355945Y416317D01*
X1357030Y417150D01*
X1357805Y418608D01*
X1357960Y420275D01*
X1357650Y421942D01*
X1356875Y422983D01*
X1355790Y423817D01*
X1354705Y424025D01*
X1353620Y423817D01*
X1352225Y422983D01*
X1352690Y428400D01*
X1356875D01*
G01X1364005Y426317D02*
X1364935Y427566D01*
X1366020Y428192D01*
X1367260Y428400D01*
X1368810Y427983D01*
X1369895Y426942D01*
X1370205Y425692D01*
X1370050Y424441D01*
X1369430Y423400D01*
X1366330Y421317D01*
X1364935Y419858D01*
X1364005Y417775D01*
X1363695Y415900D01*
X1370205D01*
G01X1329750Y444000D02*
Y456500D01*
X1327890Y454000D01*
G01Y444000D02*
X1331610D01*
G01X1338740Y445875D02*
X1339670Y444833D01*
X1340755Y444208D01*
X1342150Y444000D01*
X1343545Y444417D01*
X1344630Y445250D01*
X1345405Y446708D01*
X1345560Y448375D01*
X1345250Y450042D01*
X1344475Y451083D01*
X1343390Y451917D01*
X1342305Y452125D01*
X1341220Y451917D01*
X1339825Y451083D01*
X1340290Y456500D01*
X1344475D01*
G01X1351605Y454417D02*
X1352535Y455666D01*
X1353620Y456292D01*
X1354860Y456500D01*
X1356410Y456083D01*
X1357495Y455042D01*
X1357805Y453792D01*
X1357650Y452541D01*
X1357030Y451500D01*
X1353930Y449417D01*
X1352535Y447958D01*
X1351605Y445875D01*
X1351295Y444000D01*
X1357805D01*
G01X1366950D02*
Y456500D01*
X1365090Y454000D01*
G01Y444000D02*
X1368810D01*
G01X1342150Y303500D02*
Y316000D01*
X1340290Y313500D01*
G01Y303500D02*
X1344010D01*
G01X1354550Y316000D02*
X1353310Y315583D01*
X1352380Y314542D01*
X1351760Y313292D01*
X1351295Y311625D01*
X1351140Y309750D01*
X1351295Y307875D01*
X1351760Y306208D01*
X1352380Y304958D01*
X1353310Y303917D01*
X1354550Y303500D01*
X1355790Y303917D01*
X1356720Y304958D01*
X1357340Y306208D01*
X1357805Y307875D01*
X1357960Y309750D01*
X1357805Y311625D01*
X1357340Y313292D01*
X1356720Y314542D01*
X1355790Y315583D01*
X1354550Y316000D01*
G01X1332540Y362200D02*
X1333470Y360741D01*
X1334710Y359908D01*
X1336105Y359700D01*
X1337345Y359908D01*
X1338585Y360950D01*
X1339360Y362200D01*
X1339515Y363450D01*
X1339205Y364908D01*
X1338120Y365950D01*
X1337035Y366367D01*
X1335640D01*
G01X1337035D02*
X1337965Y366992D01*
X1338740Y368033D01*
X1339050Y369283D01*
X1338740Y370533D01*
X1337965Y371575D01*
X1336570Y372200D01*
X1335175Y371992D01*
X1333780Y371158D01*
G01X1350210Y359700D02*
Y372200D01*
X1344475Y363242D01*
X1352225D01*
G01X1357340Y362200D02*
X1358270Y360741D01*
X1359510Y359908D01*
X1360905Y359700D01*
X1362145Y359908D01*
X1363385Y360950D01*
X1364160Y362200D01*
X1364315Y363450D01*
X1364005Y364908D01*
X1362920Y365950D01*
X1361835Y366367D01*
X1360440D01*
G01X1361835D02*
X1362765Y366992D01*
X1363540Y368033D01*
X1363850Y369283D01*
X1363540Y370533D01*
X1362765Y371575D01*
X1361370Y372200D01*
X1359975Y371992D01*
X1358580Y371158D01*
G01X1339205Y398217D02*
X1340135Y399466D01*
X1341220Y400092D01*
X1342460Y400300D01*
X1344010Y399883D01*
X1345095Y398842D01*
X1345405Y397592D01*
X1345250Y396341D01*
X1344630Y395300D01*
X1341530Y393217D01*
X1340135Y391758D01*
X1339205Y389675D01*
X1338895Y387800D01*
X1345405D01*
G01X1351140Y390300D02*
X1352070Y388841D01*
X1353310Y388008D01*
X1354705Y387800D01*
X1355945Y388008D01*
X1357185Y389050D01*
X1357960Y390300D01*
X1358115Y391550D01*
X1357805Y393008D01*
X1356720Y394050D01*
X1355635Y394467D01*
X1354240D01*
G01X1355635D02*
X1356565Y395092D01*
X1357340Y396133D01*
X1357650Y397383D01*
X1357340Y398633D01*
X1356565Y399675D01*
X1355170Y400300D01*
X1353775Y400092D01*
X1352380Y399258D01*
G01X1335950Y473650D02*
X1334710Y473858D01*
X1333625Y474691D01*
X1332695Y475942D01*
X1332075Y477400D01*
X1331765Y479067D01*
Y480733D01*
X1332075Y482400D01*
X1332695Y483858D01*
X1333625Y485108D01*
X1334710Y485942D01*
X1335950Y486150D01*
X1337190Y485942D01*
X1338275Y485108D01*
X1339205Y483858D01*
X1339825Y482400D01*
X1340135Y480733D01*
Y479067D01*
X1339825Y477400D01*
X1339205Y475942D01*
X1338275Y474691D01*
X1337190Y473858D01*
X1335950Y473650D01*
G01X1337190Y476983D02*
X1339050Y473650D01*
G01X1348350Y486150D02*
Y473650D01*
G01X1344785Y486150D02*
X1351915D01*
G01X1360750Y473650D02*
Y479275D01*
X1357650Y486150D01*
G01X1363850D02*
X1360750Y479275D01*
G01X1348350Y50600D02*
Y63100D01*
X1346490Y60600D01*
G01Y50600D02*
X1350210D01*
G01Y78700D02*
Y91200D01*
X1344475Y82242D01*
X1352225D01*
G01X1345405Y117217D02*
X1346335Y118466D01*
X1347420Y119092D01*
X1348660Y119300D01*
X1350210Y118883D01*
X1351295Y117842D01*
X1351605Y116592D01*
X1351450Y115341D01*
X1350830Y114300D01*
X1347730Y112217D01*
X1346335Y110758D01*
X1345405Y108675D01*
X1345095Y106800D01*
X1351605D01*
G01X1345405Y145317D02*
X1346335Y146566D01*
X1347420Y147192D01*
X1348660Y147400D01*
X1350210Y146983D01*
X1351295Y145942D01*
X1351605Y144692D01*
X1351450Y143441D01*
X1350830Y142400D01*
X1347730Y140317D01*
X1346335Y138858D01*
X1345405Y136775D01*
X1345095Y134900D01*
X1351605D01*
G01X1344940Y165500D02*
X1345870Y164041D01*
X1347110Y163208D01*
X1348505Y163000D01*
X1349745Y163208D01*
X1350985Y164250D01*
X1351760Y165500D01*
X1351915Y166750D01*
X1351605Y168208D01*
X1350520Y169250D01*
X1349435Y169667D01*
X1348040D01*
G01X1349435D02*
X1350365Y170292D01*
X1351140Y171333D01*
X1351450Y172583D01*
X1351140Y173833D01*
X1350365Y174875D01*
X1348970Y175500D01*
X1347575Y175292D01*
X1346180Y174458D01*
G01X1348350Y191100D02*
Y203600D01*
X1346490Y201100D01*
G01Y191100D02*
X1350210D01*
G01X1344940Y221075D02*
X1345870Y220033D01*
X1346955Y219408D01*
X1348350Y219200D01*
X1349745Y219617D01*
X1350830Y220450D01*
X1351605Y221908D01*
X1351760Y223575D01*
X1351450Y225242D01*
X1350675Y226283D01*
X1349590Y227117D01*
X1348505Y227325D01*
X1347420Y227117D01*
X1346025Y226283D01*
X1346490Y231700D01*
X1350675D01*
G01X1345405Y252508D02*
X1346490Y253967D01*
X1347420Y254800D01*
X1348660Y255217D01*
X1349745Y254800D01*
X1350520Y253967D01*
X1351140Y252717D01*
X1351295Y251258D01*
X1351140Y250008D01*
X1350520Y248758D01*
X1349590Y247717D01*
X1348505Y247300D01*
X1347265Y247717D01*
X1346180Y248966D01*
X1345560Y250842D01*
X1345405Y252925D01*
X1345715Y255633D01*
X1346180Y257092D01*
X1346955Y258550D01*
X1348040Y259592D01*
X1349125Y259800D01*
X1350210Y259383D01*
X1350985Y258342D01*
G01X1345405Y285817D02*
X1346335Y287066D01*
X1347420Y287692D01*
X1348660Y287900D01*
X1350210Y287483D01*
X1351295Y286442D01*
X1351605Y285192D01*
X1351450Y283941D01*
X1350830Y282900D01*
X1347730Y280817D01*
X1346335Y279358D01*
X1345405Y277275D01*
X1345095Y275400D01*
X1351605D01*
G01X1350210Y331600D02*
Y344100D01*
X1344475Y335142D01*
X1352225D01*
G01X336447Y214653D02*
Y218653D01*
X335647Y217853D01*
G01Y214653D02*
X337247D01*
G01X341047D02*
X341514Y214720D01*
X342047Y214920D01*
X342380Y215253D01*
X342514Y215720D01*
X342380Y216186D01*
X341980Y216586D01*
X341380Y216786D01*
X340714D01*
X340314Y216920D01*
X339980Y217253D01*
X339847Y217720D01*
X340047Y218186D01*
X340514Y218520D01*
X341047Y218653D01*
X341580Y218520D01*
X342047Y218186D01*
X342247Y217720D01*
X342114Y217253D01*
X341780Y216920D01*
X341380Y216786D01*
X340714D01*
X340114Y216586D01*
X339714Y216186D01*
X339580Y215720D01*
X339714Y215253D01*
X340047Y214920D01*
X340580Y214720D01*
X341047Y214653D01*
G01X344514Y215120D02*
X344980Y214786D01*
X345514Y214653D01*
X346047Y214786D01*
X346514Y215186D01*
X346847Y215786D01*
X346980Y216386D01*
Y217120D01*
X346847Y217720D01*
X346514Y218253D01*
X346114Y218520D01*
X345647Y218653D01*
X345114Y218520D01*
X344714Y218253D01*
X344447Y217853D01*
X344314Y217320D01*
X344447Y216853D01*
X344780Y216386D01*
X345180Y216120D01*
X345647Y216053D01*
X346180Y216186D01*
X346580Y216520D01*
X346980Y217120D01*
G01X348847Y214653D02*
X351647Y218653D01*
G01X348847D02*
X351647Y214653D01*
G01X354847D02*
Y218653D01*
X354047Y217853D01*
G01Y214653D02*
X355647D01*
G01X358180Y217986D02*
X358580Y218386D01*
X359047Y218586D01*
X359580Y218653D01*
X360247Y218520D01*
X360714Y218186D01*
X360847Y217786D01*
X360780Y217386D01*
X360514Y217053D01*
X359180Y216386D01*
X358580Y215920D01*
X358180Y215253D01*
X358047Y214653D01*
X360847D01*
G01X362780Y216320D02*
X363247Y216786D01*
X363647Y217053D01*
X364180Y217186D01*
X364647Y217053D01*
X364980Y216786D01*
X365247Y216386D01*
X365314Y215920D01*
X365247Y215520D01*
X364980Y215120D01*
X364580Y214786D01*
X364114Y214653D01*
X363580Y214786D01*
X363114Y215186D01*
X362847Y215786D01*
X362780Y216453D01*
X362914Y217320D01*
X363114Y217786D01*
X363447Y218253D01*
X363914Y218586D01*
X364380Y218653D01*
X364847Y218520D01*
X365180Y218186D01*
G54D17*
X144000Y67875D03*
Y147125D03*
X948450Y281650D03*
G54D18*
X196800Y62600D03*
X199600Y160100D03*
X239300Y196800D03*
X502500Y6200D03*
X538300Y15200D03*
X699000Y162255D03*
X756400Y110500D03*
X786500Y13500D03*
X784000Y31000D03*
X782000Y137000D03*
X790500Y11000D03*
X799000Y121500D03*
Y125500D03*
X800400Y158500D03*
X799900Y168800D03*
X811000Y130000D03*
Y134000D03*
X809000Y149200D03*
X811000Y138000D03*
X811200Y141600D03*
X809500Y156900D03*
X809600Y160500D03*
X809700Y164300D03*
X948450Y394050D03*
G54D19*
X200197Y282677D03*
X298622D03*
X948450Y141150D03*
M02*
